G04 ================== begin FILE IDENTIFICATION RECORD ==================*
G04 Layout Name:  15105-sa.brd*
G04 Film Name:    L3*
G04 File Format:  Gerber RS274X*
G04 File Origin:  Cadence Allegro 16.5-S056*
G04 Origin Date:  Wed Nov 16 02:02:16 2016*
G04 *
G04 Layer:  VIA CLASS/L3*
G04 Layer:  PIN/L3*
G04 Layer:  ETCH/L3*
G04 Layer:  DRAWING FORMAT/LAYER_PCB_STORY*
G04 Layer:  DRAWING FORMAT/LAYER_L3*
G04 *
G04 Offset:    (0.00 0.00)*
G04 Mirror:    No*
G04 Mode:      Positive*
G04 Rotation:  0*
G04 FullContactRelief:  No*
G04 UndefLineWidth:     6.00*
G04 ================== end FILE IDENTIFICATION RECORD ====================*
%FSLAX35Y35*MOIN*%
%IR0*IPPOS*OFA0.00000B0.00000*MIA0B0*SFA1.00000B1.00000*%
%ADD10C,.02*%
%ADD14C,.022*%
%ADD17C,.05*%
%ADD11C,.018*%
%ADD13C,.028*%
%ADD16C,.029*%
%ADD12C,.056*%
%ADD15C,.058*%
%ADD18C,.01*%
%ADD19C,.012*%
%ADD20C,.015*%
%ADD21C,.025*%
%ADD22C,.017*%
%ADD23C,.004*%
%ADD24C,.006*%
%ADD25C,.005*%
%ADD26C,.0055*%
%ADD34C,.08004*%
%ADD32C,.04404*%
%ADD33C,.02704*%
%ADD31C,.09004*%
%ADD27C,.11004*%
%ADD29C,.3151*%
%ADD28C,.31532*%
%ADD30C,.31534*%
G75*
%LPD*%
G75*
G36*
G01X371000Y111000D02*
X474356Y7644D01*
G02X486884Y-7523I-3342J-15518D01*
G01X486638Y-7769D01*
Y-7977D01*
X486784Y-8123D01*
X486888D01*
Y-11685D01*
X495117D01*
Y-16681D01*
X486762D01*
G02X481892Y-11811I0J4870D01*
G01Y-7874D01*
G03X471014Y3004I-10878J0D01*
G01X212402D01*
G02X207532Y7874I0J4870D01*
G01Y94528D01*
G03X196654Y105406I-10878J0D01*
G01X7874D01*
G02X3004Y110276I0J4870D01*
G01Y836614D01*
G02X3937Y837547I933J0D01*
G01X100000D01*
G03X102368Y837900I0J8122D01*
G02X102885Y837518I117J-382D01*
G01Y832872D01*
G02X100002Y832551I-2884J12797D01*
G01X8000D01*
Y400100D01*
X15298Y392802D01*
Y321811D01*
X18500Y318610D01*
Y161100D01*
X23588Y156012D01*
G02X23572Y155431I-283J-283D01*
G03X30789Y148214I3404J-3813D01*
G02X31370Y148230I298J-267D01*
G01X47570Y132030D01*
X146716D01*
X164384Y114362D01*
X208052D01*
X212298Y110115D01*
Y86095D01*
X216110Y82284D01*
Y67200D01*
X226000Y57310D01*
X262540D01*
X269750Y64520D01*
Y106960D01*
X273790Y111000D01*
X371000D01*
G37*
G36*
G01X102900Y585800D02*
X91400Y597300D01*
X82146D01*
G03X78454I-1846J-1200D01*
G01X64000D01*
X62600Y598700D01*
Y603500D01*
X102700Y643600D01*
X114801D01*
G03X118301I1750J1336D01*
G01X148219D01*
X148252Y643440D01*
G03X148706Y642488I2157J444D01*
G02X148677Y642207I-155J-126D01*
G03X148696Y638779I1392J-1706D01*
G02X148728Y638182I-250J-313D01*
G03X151653Y638341I1552J-1562D01*
G02X151621Y638938I250J313D01*
G03X151772Y641896I-1552J1562D01*
G02X151801Y642177I155J126D01*
G03X152566Y643440I-1392J1706D01*
G01X152599Y643600D01*
X212800D01*
X242500Y613900D01*
Y600200D01*
X239500Y597200D01*
X200065D01*
G02X199840Y597930I1J400D01*
G03X197360I-1240J1820D01*
G02X197135Y597200I-226J-330D01*
G01X189700D01*
X178300Y585800D01*
X102900D01*
G37*
G36*
G01X228900Y675400D02*
X220300Y684000D01*
X211403D01*
X211401Y684002D01*
X191600D01*
G02X191200Y684417I0J400D01*
G03X187307Y685909I-2200J83D01*
G02X186693I-307J255D01*
G03X182800Y684417I-1693J-1409D01*
G02X182400Y684002I-400J-15D01*
G01X168538D01*
G02X168302Y684724I1J400D01*
G03X165698I-1302J1776D01*
G02X165462Y684002I-237J-322D01*
G01X143498D01*
X112000Y715500D01*
Y716177D01*
X112133Y716224D01*
G03Y720376I-733J2076D01*
G01X112000Y720423D01*
Y739677D01*
X112133Y739724D01*
G03Y743876I-733J2076D01*
G01X112000Y743923D01*
Y753908D01*
X112125Y753958D01*
G03X113063Y757320I-825J2042D01*
G01X112959Y757459D01*
X130500Y775000D01*
Y800500D01*
X143000Y813000D01*
X185500D01*
X199278Y799222D01*
G02X199134Y798564I-283J-283D01*
G03X201458Y794944I766J-2064D01*
G02X201742I142J-141D01*
G03X203952Y794397I1558J1556D01*
G01X204067Y794433D01*
X226811Y771689D01*
X226823Y771668D01*
G03X227518Y770973I1727J1032D01*
G01X227539Y770961D01*
X255500Y743000D01*
X260989D01*
G03X264267I1639J1470D01*
G01X317500D01*
X319500Y741000D01*
Y728500D01*
X318015Y727015D01*
G02X317332Y727282I-283J283D01*
G03X315514Y725028I-2200J-85D01*
G01X315616Y725046D01*
X315831Y724831D01*
X315500Y724500D01*
Y680800D01*
X310100Y675400D01*
X228900D01*
G37*
G36*
G01X317800Y261200D02*
X302700Y276300D01*
X217407D01*
G03X210393I-3507J-1928D01*
G01X207407D01*
G03X200393I-3507J-1928D01*
G01X197407D01*
G03X190393I-3507J-1928D01*
G01X188297D01*
X188098Y276101D01*
G02X187460Y276201I-282J283D01*
G03X187218Y272135I-3560J-1828D01*
G02X187950Y271911I332J-223D01*
G01Y268998D01*
X183052Y264100D01*
X155700D01*
X154600Y265200D01*
Y267200D01*
X193900Y306500D01*
X268760D01*
G03X270938I1089J1914D01*
G01X275046D01*
G02X275393Y305900I0J-400D01*
G03X279207I1907J-1100D01*
G02X279554Y306500I347J200D01*
G01X302124D01*
X306973Y301652D01*
X313838D01*
X331050Y284439D01*
Y262550D01*
X329700Y261200D01*
X317800D01*
G37*
G36*
G01X329563Y508800D02*
X329602Y508918D01*
G03X327452Y511813I-2090J694D01*
G01X327366Y511811D01*
X319875Y519302D01*
X319062D01*
X317843Y520520D01*
Y594391D01*
X307125Y605109D01*
X262700D01*
X246428Y621381D01*
Y653926D01*
X253746Y661244D01*
X347592D01*
X534771Y474065D01*
Y462610D01*
X519818Y447657D01*
X390707D01*
X329563Y508800D01*
G37*
G36*
G01X455118Y832551D02*
G02X442000Y845669I0J13118D01*
G01Y866157D01*
X446996D01*
Y845669D01*
G03X455118Y837547I8122J0D01*
G01X517323D01*
G03X525445Y845669I0J8122D01*
G01Y866157D01*
X530441D01*
Y845669D01*
G02X528173Y838297I-13118J1D01*
G03X525457Y835378I-673J-2097D01*
G02X517323Y832551I-8135J10291D01*
G01X502741D01*
G03X498873I-1934J-1052D01*
G01X455118D01*
G37*
G36*
G01X529652Y769000D02*
G03X528482Y769570I-1552J-1700D01*
G01X528419Y769581D01*
X525000Y773000D01*
X520300D01*
X519002Y771702D01*
X518349D01*
X516446Y769799D01*
Y767349D01*
X516297Y767200D01*
X514300D01*
X513893Y767607D01*
X513924Y767719D01*
G03X513700Y769413I-2124J581D01*
G01Y771200D01*
X511900Y773000D01*
X479000D01*
X475500Y776500D01*
Y821500D01*
X476500Y822500D01*
X532500D01*
X535000Y820000D01*
Y783201D01*
X534831Y783175D01*
G03Y778825I347J-2175D01*
G01X535000Y778799D01*
Y772000D01*
X532000Y769000D01*
X529652D01*
G37*
G36*
G01X535048Y292967D02*
X534100Y293915D01*
Y296576D01*
G03Y300296I-1179J1860D01*
G01Y313683D01*
X550664Y330247D01*
X561193D01*
X562028Y329412D01*
Y322627D01*
X560984Y321583D01*
X558667D01*
X558637Y321592D01*
G03X557089I-774J-2484D01*
G01X557059Y321583D01*
X554267D01*
X554237Y321592D01*
G03X552689I-774J-2484D01*
G01X552659Y321583D01*
X552497D01*
X552395Y321481D01*
X552363Y321466D01*
G03X551105Y320208I1100J-2358D01*
G01X551090Y320176D01*
X550257Y319343D01*
Y294981D01*
X548243Y292967D01*
X535048D01*
G37*
G36*
G01X1001931Y466319D02*
X971625Y501103D01*
X850055Y677430D01*
X842000Y712500D01*
Y724500D01*
X844000Y726500D01*
X870000D01*
X881650Y738150D01*
Y743550D01*
X882900Y744800D01*
X889901D01*
X892002Y742698D01*
X898298D01*
X900399Y744800D01*
X903119D01*
X913819Y755500D01*
Y820866D01*
G03X902134Y832551I-11685J0D01*
G01X872441D01*
G02X859323Y845669I0J13118D01*
G01Y864755D01*
X864319D01*
Y845669D01*
G03X872441Y837547I8122J0D01*
G01X902134D01*
G02X918815Y820866I0J-16681D01*
G01Y650669D01*
G03X926819Y642665I8004J0D01*
G01X983748D01*
G03X991752Y650669I0J8004D01*
G01Y820866D01*
G02X1008433Y837547I16681J0D01*
G01X1013386D01*
G03X1021508Y845669I0J8122D01*
G01Y867058D01*
X1025300D01*
X1026358Y866000D01*
X1026504D01*
Y845669D01*
G02X1023948Y837889I-13118J0D01*
G01X1034648Y748375D01*
X1059789Y607520D01*
X1033270Y481817D01*
X1017772Y466319D01*
X1001931D01*
G37*
G36*
G01X900200Y779415D02*
Y750602D01*
G03X899862Y746664I799J-2052D01*
G02X899939Y746039I-206J-343D01*
G01X897800Y743900D01*
X892500D01*
X890200Y746200D01*
X878846D01*
G03X875607Y746705I-1846J-1200D01*
G02X875048Y746757I-253J310D01*
G03X871761Y746842I-1681J-1422D01*
G02X871153Y746872I-291J274D01*
G03X867737Y746967I-1747J-1341D01*
G02X867122Y746978I-303J261D01*
G03X863690I-1716J-1380D01*
G02X863075Y746967I-312J250D01*
G03X859737I-1669J-1436D01*
G02X859122Y746978I-303J261D01*
G03X855330Y746333I-1716J-1380D01*
G01X855283Y746200D01*
X849100D01*
X840700Y754600D01*
Y773200D01*
X844400Y776900D01*
Y799200D01*
X845200Y800000D01*
X857200D01*
X866500Y790700D01*
X892000D01*
X899160Y783540D01*
G02X899176Y782992I-283J-282D01*
G03X900069Y779463I1648J-1460D01*
G01X900200Y779415D01*
G37*
G36*
G01X1001500Y163000D02*
X998000Y159500D01*
Y144000D01*
X997000Y143000D01*
X992000D01*
X989500Y145500D01*
Y146645D01*
G03Y148631I-918J993D01*
G01Y150582D01*
G03Y152568I-918J993D01*
G01Y158456D01*
G03X989556Y160387I-918J993D01*
G01X989500Y160445D01*
Y160500D01*
X985500Y164500D01*
X985413D01*
X985364Y164531D01*
G03X983879Y164500I-719J-1145D01*
G01X981474D01*
G03X979942I-766J-1114D01*
G01X977537D01*
G03X976005I-766J-1114D01*
G01X973600D01*
G03X972068I-766J-1114D01*
G01X969663D01*
G03X968131I-766J-1114D01*
G01X965726D01*
G03X964194I-766J-1114D01*
G01X961789D01*
G03X960257I-766J-1114D01*
G01X957852D01*
G03X956320I-766J-1114D01*
G01X953915D01*
G03X952383I-766J-1114D01*
G01X949978D01*
G03X948446I-766J-1114D01*
G01X942105D01*
G03X940573I-766J-1114D01*
G01X938168D01*
G03X936636I-766J-1114D01*
G01X934231D01*
G03X932699I-766J-1114D01*
G01X930500D01*
Y166383D01*
G03Y168263I-972J940D01*
G01Y170320D01*
G03Y172200I-972J940D01*
G01Y174257D01*
G03Y176137I-972J940D01*
G01Y178194D01*
G03Y180074I-972J940D01*
G01Y180500D01*
X930000Y181000D01*
X896500D01*
X895500Y182000D01*
Y190489D01*
X895509Y190517D01*
G03Y191371I-1414J427D01*
G01X895500Y191399D01*
Y200000D01*
X893500Y202000D01*
Y203500D01*
X895500Y205500D01*
Y234500D01*
X895469Y234531D01*
X895456Y234585D01*
G03X894429Y235612I-1361J-334D01*
G01X894375Y235625D01*
X893000Y237000D01*
Y238500D01*
X894500Y240000D01*
X1000000D01*
X1000659Y239341D01*
X1000636Y239235D01*
G03X1000579Y238703I2463J-533D01*
G01Y238701D01*
X1000578Y238700D01*
Y237078D01*
X998500Y235000D01*
Y206500D01*
X1000000Y205000D01*
X1001000D01*
X1001500Y204500D01*
Y202500D01*
X1000500Y201500D01*
X999500D01*
X998500Y200500D01*
Y167500D01*
X999112Y166888D01*
X999127Y166847D01*
G03X999917Y166057I1266J476D01*
G01X999958Y166042D01*
X1001500Y164500D01*
Y163000D01*
G37*
G36*
G01X967500Y131000D02*
X968608Y129892D01*
G02X968456Y129231I-283J-283D01*
G03X970030Y128691I441J-1278D01*
G01X969997Y128741D01*
Y129000D01*
X970328D01*
X971207Y128120D01*
X975415D01*
X975419Y127925D01*
G03X978123I1352J28D01*
G01X978127Y128120D01*
X980843D01*
X980890Y128073D01*
Y125890D01*
X980500Y125500D01*
X955000D01*
X954000Y126500D01*
Y126902D01*
G03Y129004I-851J1051D01*
G01Y130839D01*
G03Y132941I-851J1051D01*
G01Y134776D01*
G03Y136878I-851J1051D01*
G01Y138713D01*
G03Y140815I-851J1051D01*
G01Y142650D01*
G03Y144752I-851J1051D01*
G01Y145000D01*
X950000Y149000D01*
X949543D01*
X949521Y149005D01*
G03X948903I-309J-1367D01*
G01X948881Y149000D01*
X946000D01*
X942500Y152500D01*
X942328D01*
X942270Y152555D01*
G03X940353Y152500I-931J-980D01*
G01X938388D01*
G03X936589Y152655I-986J-925D01*
G01X936450Y152550D01*
X935000Y154000D01*
Y159500D01*
X937000Y161500D01*
X969500D01*
X970000Y161000D01*
Y160711D01*
G02X969684Y160549I-200J1D01*
G03X969440Y158211I-787J-1100D01*
G02X970000Y157844I160J-367D01*
G01Y157117D01*
G02X969440Y156750I-400J0D01*
G03Y154274I-543J-1238D01*
G02X970000Y153907I160J-367D01*
G01Y151000D01*
X967500Y148500D01*
Y147750D01*
X967499Y147743D01*
G03Y147533I1398J-105D01*
G01X967500Y147526D01*
Y135939D01*
X967499Y135932D01*
G03Y135722I1398J-105D01*
G01X967500Y135715D01*
Y131000D01*
G37*
G36*
G01X1019591Y-16681D02*
X1019430Y-16520D01*
Y-11685D01*
X1025971D01*
G03X1029473I1751J2560D01*
G01X1052743D01*
G03X1056245I1751J2560D01*
G01X1075711D01*
X1075713Y-11686D01*
X1076132D01*
X1077633Y-13186D01*
X1077634D01*
X1077650Y-13202D01*
X1285410D01*
X1286928Y-11685D01*
X1298102D01*
Y-8123D01*
X1303098D01*
Y-15748D01*
G02X1302165Y-16681I-933J0D01*
G01X1019591D01*
G37*
G36*
G01X1268804Y-4000D02*
X1302500Y29696D01*
Y123405D01*
X1302621Y123457D01*
G03Y127501I-872J2022D01*
G01X1302500Y127553D01*
Y131202D01*
X1303494Y135883D01*
X1302500Y140565D01*
Y170729D01*
X1302830Y171059D01*
X1302839Y171066D01*
G03X1303332Y171559I-1719J2212D01*
G01X1303339Y171568D01*
X1317202Y185431D01*
X1353872D01*
X1359916Y179387D01*
Y177432D01*
X1359620Y177136D01*
Y172397D01*
X1358080Y170857D01*
X1357550D01*
X1357466Y170940D01*
X1353795D01*
X1353712Y170858D01*
X1350319D01*
X1345342Y165882D01*
X1338310D01*
X1338308Y165880D01*
X1320224D01*
X1311500Y157156D01*
Y150027D01*
X1311048Y149575D01*
Y27732D01*
X1274538Y-8778D01*
X1082734D01*
X1074991Y-1035D01*
X1074997Y-945D01*
G03X1072655Y1397I-2197J145D01*
G01X1072565Y1391D01*
X1072478Y1478D01*
X1039322D01*
X1035986Y4814D01*
Y8700D01*
X1039386Y12100D01*
X1050500D01*
X1054900Y7700D01*
X1061900D01*
X1063400Y9200D01*
Y11600D01*
X1063716Y11916D01*
X1064932D01*
X1067336Y14320D01*
Y17032D01*
X1071332Y21028D01*
X1074360D01*
X1080775Y14613D01*
X1080773Y14527D01*
G03X1083650Y12371I2201J-60D01*
G01X1083766Y12409D01*
X1084088Y12087D01*
G02X1083958Y11435I-283J-283D01*
G03X1083086Y10782I843J-2034D01*
G02X1082451Y10797I-312J251D01*
G03X1082386Y8118I-1779J-1297D01*
G02X1083021Y8103I312J-251D01*
G03X1086835Y8558I1779J1297D01*
G02X1087487Y8688I369J-153D01*
G01X1100175Y-4000D01*
X1268804D01*
G37*
G36*
G01X1298102Y-6203D02*
Y-3937D01*
G02X1298859Y246I11937J0D01*
G01X1305856Y7243D01*
G02X1310039Y8000I4183J-11180D01*
G01X1368463D01*
G03X1385424Y7969I8505J13259D01*
G01X1385474Y8000D01*
X1392000D01*
Y16549D01*
X1392009Y16578D01*
G03Y25940I-15041J4681D01*
G01X1392000Y25969D01*
Y31342D01*
G02X1386685Y40157I4653J8816D01*
G01Y71654D01*
G02X1392000Y80469I9968J-1D01*
G01Y85841D01*
X1392009Y85870D01*
G03X1392000Y95261I-15041J4681D01*
G01Y832551D01*
X1368504D01*
G02X1355386Y845669I0J13118D01*
G01Y866251D01*
X1360382D01*
Y845669D01*
G03X1368504Y837547I8122J0D01*
G01X1396063D01*
G02X1396996Y836614I0J-933D01*
G01Y77025D01*
G02X1396600Y76626I-400J1D01*
G03X1391681Y71654I54J-4972D01*
G01Y40157D01*
G03X1396600Y35185I4973J0D01*
G02X1396996Y34786I-4J-400D01*
G01Y3937D01*
G02X1396063Y3004I-933J0D01*
G01X1310039D01*
G03X1303098Y-3937I0J-6941D01*
G01Y-6203D01*
X1298102D01*
G37*
G36*
G01X1299695Y663805D02*
X1299699Y663893D01*
G03X1297393Y666199I-2199J107D01*
G01X1297305Y666195D01*
X1295500Y668000D01*
Y702000D01*
X1288000Y709500D01*
Y727500D01*
X1288500Y728000D01*
X1294500D01*
X1295500Y727000D01*
Y713000D01*
X1304500Y704000D01*
X1336500D01*
X1339000Y701500D01*
Y694500D01*
X1337500Y693000D01*
X1311000D01*
X1306679Y688679D01*
X1306617Y688669D01*
G03X1306000Y684538I383J-2169D01*
G01Y681000D01*
X1323000Y664000D01*
Y398000D01*
X1315000Y390000D01*
X1310000D01*
X1308000Y392000D01*
Y396000D01*
X1312000Y400000D01*
Y651500D01*
X1299695Y663805D01*
G37*
%LPC*%
G75*
G36*
G01X365945Y76624D02*
G02X370914Y71654I-1J-4970D01*
G01Y40157D01*
G02X365945Y35188I-4969J0D01*
G01X356102D01*
G02X351132Y40157I0J4970D01*
G01Y71654D01*
G02X356102Y76624I4970J0D01*
G01X365945D01*
G37*
G36*
G01X103433Y597328D02*
G03X103412Y597045I130J-152D01*
G02X100317Y597272I-1662J-1445D01*
G03X100338Y597555I-130J152D01*
G02X100370Y600481I1662J1445D01*
G03Y601019I-296J269D01*
G02X103630I1630J1481D01*
G03Y600481I296J-269D01*
G02X103433Y597328I-1630J-1481D01*
G37*
G36*
G01X145019Y782870D02*
G03X144481I-269J-296D01*
G02Y786130I-1481J1630D01*
G03X145019I269J296D01*
G02Y782870I1481J-1630D01*
G37*
G36*
G01X161958Y772556D02*
G03X162242I142J141D01*
G02Y769444I1558J-1556D01*
G03X161958I-142J-141D01*
G02Y772556I-1558J1556D01*
G37*
G36*
G01X169158Y766456D02*
G03X169442I142J141D01*
G02Y763344I1558J-1556D01*
G03X169158I-142J-141D01*
G02Y766456I-1558J1556D01*
G37*
G36*
G01X184519Y759370D02*
G03X183981I-269J-296D01*
G02Y762630I-1481J1630D01*
G03X184519I269J296D01*
G02Y759370I1481J-1630D01*
G37*
G36*
G01X201458Y749056D02*
G03X201742I142J141D01*
G02Y745944I1558J-1556D01*
G03X201458I-142J-141D01*
G02Y749056I-1558J1556D01*
G37*
G36*
G01Y742556D02*
G03X201742I142J141D01*
G02Y739444I1558J-1556D01*
G03X201458I-142J-141D01*
G02Y742556I-1558J1556D01*
G37*
G36*
G01X152219Y727770D02*
G03X151681I-269J-296D01*
G02Y731030I-1481J1630D01*
G03X152219I269J296D01*
G02Y727770I1481J-1630D01*
G37*
G36*
G01X145956Y730042D02*
G03Y729758I141J-142D01*
G02X142844I-1556J-1558D01*
G03Y730042I-141J142D01*
G02X145956I1556J1558D01*
G37*
G36*
G01X287662Y726863D02*
G03X287500Y726630I35J-197D01*
G02X283402Y727300I-2167J-389D01*
G03X283068Y727892I-351J192D01*
G02X285220Y730873I93J2200D01*
G03X285853Y730710I374J142D01*
G02X289471Y728829I1425J-1679D01*
G03X290000Y728414I398J-37D01*
G02X288527Y726535I720J-2081D01*
G03X287998Y726950I-398J37D01*
G02X287662Y726863I-718J2081D01*
G37*
G36*
G01X298711Y726396D02*
G03X298329Y726023I17J-400D01*
G02X296041Y728371I-2197J148D01*
G03X296423Y728744I-17J400D01*
G02X300795Y728940I2197J-148D01*
G03X301209Y728603I395J62D01*
G02X299135Y726059I101J-2200D01*
G03X298721Y726396I-395J-62D01*
G01X298711D01*
G37*
G36*
G01X242630Y720019D02*
G03Y719481I296J-269D01*
G02X239370I-1630J-1481D01*
G03Y720019I-296J269D01*
G02X239591Y723193I1630J1481D01*
G03Y723807I-255J307D01*
G02X242409I1409J1693D01*
G03Y723193I255J-307D01*
G02X242630Y720019I-1409J-1693D01*
G37*
G36*
G01X169158Y717456D02*
G03X169442I142J141D01*
G02Y714344I1558J-1556D01*
G03X169158I-142J-141D01*
G02Y717456I-1558J1556D01*
G37*
G36*
G01X292468Y714282D02*
G03X291915Y714263I-267J-298D01*
G02X288417Y714724I-1577J1537D01*
G03X287812Y714837I-349J-195D01*
G02X284690Y715151I-1406J1694D01*
G03X284075Y715162I-312J-250D01*
G02X280737I-1669J1436D01*
G03X280122Y715151I-303J-261D01*
G02X276690I-1716J1380D01*
G03X276075Y715162I-312J-250D01*
G02X276122Y717978I-1669J1436D01*
G03X276737Y717967I312J250D01*
G02X280075I1669J-1436D01*
G03X280690Y717978I303J261D01*
G02X284122I1716J-1380D01*
G03X284737Y717967I312J250D01*
G02X288327Y717607I1669J-1436D01*
G03X288932Y717494I349J195D01*
G02X291738Y717500I1407J-1694D01*
G03X292290Y717541I255J308D01*
G02X292468Y714282I1710J-1541D01*
G37*
G36*
G01X132530Y712819D02*
G03Y712281I296J-269D01*
G02X129270I-1630J-1481D01*
G03Y712819I-296J269D01*
G02X132530I1630J1481D01*
G37*
G36*
G01X300724Y704609D02*
G03X300109Y704605I-306J-258D01*
G02X300088Y707422I-1703J1396D01*
G03X300703Y707426I306J258D01*
G02X304099Y707440I1704J-1395D01*
G03X304713I307J255D01*
G02Y704622I1693J-1409D01*
G03X304099I-307J-255D01*
G02X300724Y704609I-1693J1409D01*
G37*
G36*
G01X184519Y703870D02*
G03X183981I-269J-296D01*
G02Y707130I-1481J1630D01*
G03X184519I269J296D01*
G02Y703870I1481J-1630D01*
G37*
G36*
G01X201458Y693556D02*
G03X201742I142J141D01*
G02Y690444I1558J-1556D01*
G03X201458I-142J-141D01*
G02Y693556I-1558J1556D01*
G37*
G36*
G01X309305Y727058D02*
G02X307568Y728381I-2027J-860D01*
G03X307989Y728933I53J396D01*
G02X309726Y727610I2027J860D01*
G03X309305Y727058I-53J-396D01*
G37*
G36*
G01X319407Y528520D02*
G03X319330Y529135I-290J276D01*
G02X322093Y529480I1170J1865D01*
G03X322170Y528865I290J-276D01*
G02X319407Y528520I-1170J-1865D01*
G37*
G36*
G01X527156Y816261D02*
G03X526510Y816246I-318J-243D01*
G02X526450Y818837I-1810J1254D01*
G03X527096Y818852I318J243D01*
G02X527156Y816261I1810J-1254D01*
G37*
G36*
G01X498864Y815969D02*
G03X498580Y815966I-141J-142D01*
G02X498551Y819063I-1580J1534D01*
G03X498835Y819066I141J142D01*
G02X498864Y815969I1580J-1534D01*
G37*
G36*
G01X514550Y818769D02*
G03X515200Y818746I333J221D01*
G02X515109Y816182I1743J-1345D01*
G03X514459Y816205I-333J-221D01*
G02X514550Y818769I-1743J1345D01*
G37*
G36*
G01X496212Y802519D02*
G03Y801981I296J-269D01*
G02X492952I-1630J-1481D01*
G03Y802519I-296J269D01*
G02X496212I1630J1481D01*
G37*
G36*
G01X481976Y783061D02*
G03X481693Y783055I-139J-144D01*
G02X481624Y786164I-1593J1520D01*
G03X481907Y786170I139J144D01*
G02X481976Y783061I1593J-1520D01*
G37*
G36*
G01X524565Y781266D02*
G03X524918Y780728I375J-139D01*
G02X522730Y779294I-123J-2199D01*
G03X522377Y779832I-375J139D01*
G02X524565Y781266I123J2199D01*
G37*
G36*
G01X510023Y776868D02*
G03X509446Y776819I-265J-300D01*
G02X505825Y777091I-1717J1379D01*
G03X505295Y777245I-346J-201D01*
G02X502132Y778704I-1017J1953D01*
G03X501594Y778986I-390J-90D01*
G02X500529Y778843I-817J2045D01*
G03X500089Y778504I-44J-397D01*
G02X495757Y779287I-2179J320D01*
G03X495603Y779524I-196J41D01*
G02X498178Y782285I458J2154D01*
G03X498903Y782185I385J110D01*
G02X502924Y781525I1875J-1154D01*
G03X503462Y781243I390J90D01*
G02X506182Y780305I816J-2045D01*
G03X506712Y780151I346J201D01*
G02X509190Y779845I1017J-1953D01*
G03X509767Y779894I265J300D01*
G02X512827Y780260I1717J-1379D01*
G03X513411Y780365I245J317D01*
G02X513935Y777453I1867J-1167D01*
G03X513351Y777348I-245J-317D01*
G02X510023Y776868I-1867J1167D01*
G37*
G36*
G01X886959Y719735D02*
G03X886390Y719689I-262J-302D01*
G02X883126Y719560I-1690J1411D01*
G03X882588Y719591I-286J-280D01*
G02X882774Y722840I-1388J1709D01*
G03X883312Y722809I286J280D01*
G02X886141Y722765I1388J-1709D01*
G03X886710Y722811I262J302D01*
G02X890090I1690J-1411D01*
G03X890659Y722765I307J256D01*
G02X890410Y719689I1441J-1665D01*
G03X889841Y719735I-307J-256D01*
G02X886959I-1441J1665D01*
G37*
G36*
G01X866642Y706144D02*
G03X866358I-142J-141D01*
G02Y709256I-1558J1556D01*
G03X866642I142J141D01*
G02Y706144I1558J-1556D01*
G37*
G36*
G01X955342Y605444D02*
G03X955058I-142J-141D01*
G02Y608556I-1558J1556D01*
G03X955342I142J141D01*
G02X958423Y608590I1558J-1556D01*
G03X958977I277J289D01*
G02Y605410I1523J-1590D01*
G03X958423I-277J-289D01*
G02X955342Y605444I-1523J1590D01*
G37*
G36*
G01X897328Y736041D02*
G02X895080Y735683I-828J-2041D01*
G03X894972Y736359I-258J305D01*
G02X897220Y736717I828J2041D01*
G03X897328Y736041I258J-305D01*
G37*
G36*
G01X843036Y759645D02*
G03X842982Y760283I-266J299D01*
G02X845614Y760505I1168J1867D01*
G03X845668Y759867I266J-299D01*
G02X843036Y759645I-1168J-1867D01*
G37*
G36*
G01X882576Y756228D02*
G03X882184Y756633I-400J5D01*
G02X884429Y758805I43J2202D01*
G03X884821Y758400I400J-5D01*
G02X882576Y756228I-43J-2202D01*
G37*
G36*
G01X869780Y756266D02*
G03X869601Y756047I20J-199D01*
G02X867192Y758015I-2191J-223D01*
G03X867371Y758234I-20J199D01*
G02X869780Y756266I2191J223D01*
G37*
G36*
G01X896526Y757071D02*
G03X896401Y756550I226J-330D01*
G02X892839Y754016I-1936J-1049D01*
G03X892555Y754028I-148J-135D01*
G02X892682Y757126I-1499J1613D01*
G03X892966Y757114I148J135D01*
G02X893217Y757315I1498J-1614D01*
G03X893342Y757836I-226J330D01*
G02X896526Y757071I1936J1049D01*
G37*
G36*
G01X876748Y758076D02*
G03X876924Y757496I338J-214D01*
G02X874175Y756658I-888J-2015D01*
G03X873999Y757238I-338J214D01*
G02X876748Y758076I888J2015D01*
G37*
G36*
G01X859713Y753789D02*
G03X859099I-307J-255D01*
G02X855206Y755101I-1693J1409D01*
G03X854690Y755466I-399J-17D01*
G02X856249Y757670I-641J2107D01*
G03X856765Y757305I399J17D01*
G02X859099Y756607I641J-2107D01*
G03X859713I307J255D01*
G02Y753789I1693J-1409D01*
G37*
G36*
G01X1303844Y675447D02*
G03X1304459Y675436I312J250D01*
G02X1304412Y672620I1669J-1436D01*
G03X1303797Y672631I-312J-250D01*
G02X1303844Y675447I-1669J1436D01*
G37*
G36*
G01X1312049Y662444D02*
G03X1311765I-142J-141D01*
G02Y665556I-1558J1556D01*
G03X1312049I142J141D01*
G02X1315165I1558J-1556D01*
G03X1315449I142J141D01*
G02Y662444I1558J-1556D01*
G03X1315165I-142J-141D01*
G02X1312049I-1558J1556D01*
G37*
G54D34*
X1348785Y179358D03*
X1323195D03*
G54D32*
X69258Y603000D03*
X88000Y613600D03*
X94860Y628750D03*
X105851Y611436D03*
X104400Y590300D03*
X120351Y633500D03*
X126851Y633449D03*
X165851Y630651D03*
X137551Y629849D03*
X149851Y631251D03*
X155851Y631051D03*
X160851Y630651D03*
X181371Y601636D03*
X118060Y743460D03*
X132200Y761300D03*
Y756300D03*
X164500Y693500D03*
X136400Y738300D03*
Y721800D03*
X161200Y723900D03*
X157700Y748900D03*
X154000Y779000D03*
X150500Y804000D03*
X193500Y700000D03*
X190000Y725000D03*
X177700Y723900D03*
X182860Y742240D03*
X181200Y748900D03*
X190000Y780500D03*
X170500Y779000D03*
X193500Y755500D03*
X175660Y797340D03*
X174000Y804000D03*
X219000Y694000D03*
X210000Y700000D03*
X231500Y699000D03*
X213500Y725000D03*
X215160Y718340D03*
X213500Y780500D03*
X210000Y755500D03*
X215160Y773840D03*
X241000Y712500D03*
X266980Y723854D03*
X258100Y726100D03*
X285500Y704900D03*
X270000Y732650D03*
X275609Y726886D03*
X312500Y716500D03*
X180850Y285650D03*
X230400Y283400D03*
X222200Y300500D03*
X245400Y296500D03*
X267300Y300600D03*
X299600Y297662D03*
X306800Y290500D03*
X312900Y290450D03*
X256600Y652200D03*
X281800Y638900D03*
X288400Y626100D03*
Y634200D03*
X292500Y630200D03*
X271500Y639500D03*
X482925Y777422D03*
X489522Y780127D03*
X485300Y808250D03*
X528179Y782555D03*
X526274Y806000D03*
X511500Y803000D03*
X507044Y817569D03*
X855500Y775500D03*
X858695Y759900D03*
X871000Y776500D03*
X851890Y789270D03*
X884671Y775500D03*
X1072140Y16447D03*
X1084000Y500D03*
X1302000Y695500D03*
X1302128Y685500D03*
G54D33*
X131369Y610945D03*
X115622Y604646D03*
X121911Y614076D03*
X131369Y588898D03*
X121922Y592048D03*
X118771Y595196D03*
X125072Y610945D03*
X125070Y598347D03*
X131370Y601496D03*
X118773Y601495D03*
X126646Y606400D03*
X115622Y614094D03*
Y601496D03*
X121922Y610945D03*
X128220Y614095D03*
X118773Y604645D03*
X125070Y614095D03*
X118773Y598345D03*
X118805Y614099D03*
X115623Y598345D03*
X118773Y610945D03*
X131369Y614095D03*
X118773Y589748D03*
X128221Y610945D03*
X121922Y617244D03*
X128221D03*
X131369D03*
X118771D03*
X125070D03*
X143968Y614095D03*
X143967Y610945D03*
X137669Y604645D03*
X162865Y595196D03*
Y604645D03*
X156566Y610945D03*
X159716Y598345D03*
X153417Y614095D03*
X150269D03*
X153418Y595197D03*
X162865Y610945D03*
X137661Y614096D03*
X137670Y595197D03*
X147143Y595184D03*
X137669Y610945D03*
Y601495D03*
X140818D03*
X134521Y595196D03*
X134519Y614095D03*
X150269Y598347D03*
X156566Y614095D03*
X143968Y601495D03*
X140821Y614106D03*
X166016Y601496D03*
X159716Y610945D03*
Y614095D03*
Y595197D03*
X166016Y610944D03*
X162867Y614095D03*
X147115Y598360D03*
X150268Y601496D03*
X147141Y614096D03*
X143968Y588898D03*
X153417Y610945D03*
X159716Y604645D03*
X166015Y598345D03*
X147117Y610945D03*
X162865Y601495D03*
X150268Y610944D03*
X159716Y601495D03*
X140818Y610945D03*
X134520Y610944D03*
X143969Y617244D03*
X162881Y617266D03*
X153417Y617244D03*
X150251Y617226D03*
X134521Y617266D03*
X901969Y194881D03*
X905906D03*
X901969Y198818D03*
X905906D03*
X901969Y202755D03*
X905906D03*
X901969Y206692D03*
X905906D03*
X901969Y210629D03*
X905906D03*
X898032Y206692D03*
X901969Y190944D03*
X905906D03*
X901969Y222440D03*
X905906D03*
X901969Y226377D03*
X905906D03*
Y234251D03*
X901969Y230314D03*
X905906D03*
X901969Y234251D03*
Y214566D03*
X905906D03*
X901969Y218503D03*
X905906D03*
X937402Y175197D03*
X941339Y171260D03*
X937402Y167323D03*
X933465Y171260D03*
X941339Y175197D03*
Y167323D03*
X933465Y175197D03*
X937402Y171260D03*
X933465Y167323D03*
X913780Y183071D03*
X921654Y194881D03*
X917717Y198818D03*
X937402Y194881D03*
X933465Y198818D03*
X929528Y202755D03*
X925591Y206692D03*
X921654Y210629D03*
X929528Y194881D03*
X925591Y198818D03*
X921654Y202755D03*
X917717Y206692D03*
X929528Y210629D03*
X933465Y206692D03*
X937402Y202755D03*
X941339Y198818D03*
X937402Y210629D03*
X941339Y206692D03*
X925591Y190944D03*
X933465Y179134D03*
X929528Y183071D03*
X921654D03*
X941339Y190944D03*
X933465D03*
X937402Y183071D03*
X941339Y179134D03*
X917717Y190944D03*
X925591Y194881D03*
X921654Y198818D03*
X917717Y202755D03*
X933465Y210629D03*
X937402Y206692D03*
X941339Y202755D03*
Y194881D03*
X937402Y198818D03*
X933465Y202755D03*
X929528Y206692D03*
X925591Y210629D03*
X933465Y194881D03*
X929528Y198818D03*
X925591Y202755D03*
X921654Y206692D03*
X917717Y210629D03*
Y194881D03*
X937402Y179134D03*
X933465Y183071D03*
X929528Y190944D03*
X925591Y183071D03*
X937402Y190944D03*
X917717Y183071D03*
X921654Y190944D03*
X909843Y194881D03*
X913780D03*
X909843Y198818D03*
X913780D03*
X909843Y202755D03*
X913780D03*
X909843Y206692D03*
X913780D03*
X909843Y210629D03*
X913780D03*
X909843Y183071D03*
Y190944D03*
X913780D03*
Y214566D03*
X941339Y226377D03*
X937402Y222440D03*
X933465Y226377D03*
X929528Y222440D03*
X925591Y226377D03*
X929528Y230314D03*
X937402D03*
X941339Y234251D03*
X937402Y238188D03*
X933465Y234251D03*
X929528Y238188D03*
X925591Y234251D03*
Y214566D03*
X941339D03*
X933465D03*
X917717Y222440D03*
Y226377D03*
X921654Y222440D03*
Y226377D03*
X917717Y230314D03*
Y234251D03*
X921654Y230314D03*
Y234251D03*
X925591Y230314D03*
Y222440D03*
X933465D03*
X941339D03*
X937402Y226377D03*
X929528D03*
X941339Y238188D03*
Y230314D03*
X937402Y234251D03*
X933465Y238188D03*
Y230314D03*
X929528Y234251D03*
X925591Y238188D03*
X929528Y214566D03*
X921654Y218503D03*
X925591D03*
X929528D03*
X933465D03*
X937402D03*
X941339D03*
X921654Y214566D03*
X917717Y218503D03*
X937402Y214566D03*
X913780Y226377D03*
X909843Y222440D03*
X913780D03*
X909843Y226377D03*
Y230314D03*
Y234251D03*
X913780Y230314D03*
Y234251D03*
X909843Y214566D03*
Y218503D03*
X913780D03*
X949212Y167323D03*
X964960D03*
X957086Y175197D03*
X961023Y171260D03*
X953149D03*
X949212Y175197D03*
X957086Y167323D03*
X972834D03*
X968897Y171260D03*
X964960Y175197D03*
X972834D03*
X953149Y167323D03*
X949212Y171260D03*
X972834D03*
X968897Y175197D03*
Y167323D03*
X964960Y171260D03*
X961023Y175197D03*
Y167323D03*
X953149Y175197D03*
X957086Y171260D03*
X949212Y194881D03*
X968897Y198818D03*
X964960Y202755D03*
X957086Y210629D03*
X961023Y206692D03*
X972834Y194881D03*
X949212Y210629D03*
X953149Y206692D03*
X964960Y194881D03*
X961023Y198818D03*
X957086Y202755D03*
X949212D03*
X953149Y198818D03*
X957086Y194881D03*
X972834Y210629D03*
Y202755D03*
X968897Y206692D03*
X964960Y210629D03*
X949212Y183071D03*
X953149Y179134D03*
X961023D03*
X957086Y183071D03*
X953149Y190944D03*
X968897D03*
X972834Y183071D03*
X961023Y190944D03*
X964960Y183071D03*
X968897Y179134D03*
X953149Y210629D03*
X964960Y198818D03*
X961023Y202755D03*
X957086Y206692D03*
X968897Y194881D03*
X953149D03*
X949212Y198818D03*
Y206692D03*
X953149Y202755D03*
X961023Y194881D03*
X957086Y198818D03*
X972834Y206692D03*
X968897Y210629D03*
X972834Y198818D03*
X968897Y202755D03*
X964960Y206692D03*
X961023Y210629D03*
X972834Y190944D03*
X964960Y179134D03*
X961023Y183071D03*
X957086Y190944D03*
X953149Y183071D03*
X957086Y179134D03*
X949212D03*
X964960Y190944D03*
X968897Y183071D03*
X972834Y179134D03*
X968897Y226377D03*
Y234251D03*
X953149Y226377D03*
X949212Y222440D03*
Y230314D03*
X964960Y222440D03*
X961023Y226377D03*
X957086Y222440D03*
X964960Y230314D03*
X957086D03*
X953149Y234251D03*
X949212Y238188D03*
X964960D03*
X961023Y234251D03*
X957086Y238188D03*
X953149Y214566D03*
X968897D03*
X961023D03*
X972834Y222440D03*
Y226377D03*
Y230314D03*
Y234251D03*
X968897Y230314D03*
Y222440D03*
X953149D03*
X961023D03*
X949212Y226377D03*
X964960D03*
X957086D03*
X953149Y238188D03*
Y230314D03*
X949212Y234251D03*
X968897Y238188D03*
X964960Y234251D03*
X961023Y238188D03*
Y230314D03*
X957086Y234251D03*
X949212Y214566D03*
X964960D03*
X972834Y218503D03*
X949212D03*
X953149D03*
X957086Y214566D03*
X972834D03*
X957086Y218503D03*
X961023D03*
X964960D03*
X968897D03*
X976771Y171260D03*
X988582Y167323D03*
X992519D03*
X980708D03*
X984645D03*
X988582Y171260D03*
X992519D03*
X980708D03*
X984645D03*
X988582Y175197D03*
X992519D03*
X984645D03*
X992519Y159449D03*
X976771Y167323D03*
Y175197D03*
X980708Y183071D03*
X976771Y206692D03*
Y198818D03*
Y190944D03*
X980708Y198818D03*
X988582Y194881D03*
X992519D03*
X980708D03*
X984645D03*
X988582Y198818D03*
X992519D03*
X984645D03*
X988582Y202755D03*
X992519D03*
X980708D03*
X984645D03*
X988582Y206692D03*
X992519D03*
X980708D03*
X984645D03*
X988582Y210629D03*
X992519D03*
X980708D03*
X984645D03*
X996456Y206692D03*
X988582Y179134D03*
X992519D03*
X988582Y190944D03*
X992519D03*
X980708D03*
X984645D03*
X980708Y179134D03*
X984645D03*
Y183071D03*
X976771Y202755D03*
Y210629D03*
Y194881D03*
Y183071D03*
X980708Y214566D03*
X988582Y222440D03*
X992519D03*
X980708D03*
X984645D03*
X988582Y226377D03*
X992519D03*
X984645D03*
X980708D03*
X988582Y230314D03*
X992519D03*
Y234251D03*
X980708Y230314D03*
Y234251D03*
X984645Y230314D03*
Y234251D03*
X988582D03*
X984645Y214566D03*
X988582D03*
X992519D03*
X988582Y218503D03*
X992519D03*
X980708D03*
X984645D03*
X976771Y222440D03*
Y226377D03*
Y230314D03*
Y234251D03*
Y218503D03*
X937402Y155512D03*
X941339D03*
Y159449D03*
X961023Y127953D03*
X957086Y131890D03*
X964960D03*
X961023Y139764D03*
Y131890D03*
Y135827D03*
X957086D03*
X964960D03*
Y139764D03*
X949212Y155512D03*
X953149Y151575D03*
X949212Y159449D03*
X953149D03*
X949212Y151575D03*
X961023Y159449D03*
Y147638D03*
X957086Y143701D03*
X961023D03*
X957086Y151575D03*
Y147638D03*
Y155512D03*
X953149D03*
X964960Y143701D03*
X961023Y155512D03*
Y151575D03*
X964960Y155512D03*
Y151575D03*
Y147638D03*
G54D31*
X31977Y126614D03*
Y116614D03*
X91189Y126614D03*
Y116614D03*
G54D27*
X16200Y120100D03*
G54D29*
X336417Y21260D03*
G54D28*
X293110Y55906D03*
G54D30*
X336417Y90551D03*
%LPD*%
G75*
G54D10*
G01X17500Y412374D02*
Y322723D01*
X25223Y315000D01*
X28323D01*
X30623Y317300D01*
X32778D01*
X35078Y315000D01*
X41288D01*
X44988Y318700D01*
X88411D01*
X99011Y308100D01*
X103983D01*
X108715Y303368D01*
X135117D01*
X144595Y312846D01*
Y312861D01*
G01X42130Y694440D02*
X38780Y697790D01*
X29590D01*
X21080Y706300D01*
X17500D01*
G01X60700Y682100D02*
X64950Y677850D01*
X94950D01*
G01X127746Y-260199D02*
X95746D01*
G01X94950Y677850D02*
Y704150D01*
X91450Y707650D01*
G01X127746Y-276199D02*
Y-356199D01*
G01D02*
X1310146D01*
G01X127746Y-311699D02*
X1310146D01*
G01X123746Y-260199D02*
G02I-12000J0D01*
G01X118596D02*
G02I-6850J0D01*
G01X111746Y-276199D02*
Y-244199D01*
G01X127746Y-276199D02*
X1310146D01*
G01X210478Y151203D02*
Y157128D01*
X155026Y212580D01*
G01X162910Y244290D02*
Y232312D01*
X196248Y198974D01*
Y187552D01*
X221150Y162650D01*
Y140293D01*
X232543Y128900D01*
X280400D01*
X285250Y133750D01*
G01X168916Y523170D02*
X162513D01*
X157149Y528534D01*
Y543001D01*
X158748Y544600D01*
X161700D01*
X178800Y561700D01*
Y567100D01*
X182320Y570620D01*
X268765D01*
X277935Y561450D01*
X291000D01*
G01X183900Y270170D02*
Y274372D01*
G01D02*
Y278574D01*
G01X179698Y274372D02*
X183900D01*
G01X214794Y212100D02*
X225600D01*
X240200Y226700D01*
X244300D01*
G01X254000Y131500D02*
X256250Y133750D01*
X274250D01*
G01X277800Y208500D02*
X267000D01*
X248800Y226700D01*
X244300D01*
G01X264500Y521309D02*
X267648D01*
X282657Y506300D01*
X293999D01*
X325780Y474519D01*
Y471579D01*
X354897Y442462D01*
X554120D01*
X579082Y417500D01*
X618600D01*
X619100Y418000D01*
G01X274250Y133750D02*
X280150D01*
X282850Y136450D01*
X285350D01*
X290000Y141100D01*
G01X498000Y194200D02*
Y177000D01*
X496000Y175000D01*
Y173900D01*
X493500Y171400D01*
X486183D01*
X479983Y177600D01*
X472200D01*
X470000Y175400D01*
X441400D01*
X440000Y176800D01*
X433400D01*
G01X496782Y134315D02*
X486645D01*
X474990Y122660D01*
G01X473231Y274930D02*
Y235560D01*
G01X582400Y209300D02*
X565969Y225731D01*
X516392D01*
X494000Y248123D01*
Y265000D01*
X486550Y272450D01*
Y290250D01*
X480532Y296268D01*
Y321332D01*
G01X529126Y342336D02*
X518493D01*
X500198Y324041D01*
G01X559973Y387638D02*
X551937D01*
X547400Y383101D01*
Y380437D01*
X540807Y373844D01*
X532398D01*
X512942Y393300D01*
X487000D01*
G01X522646Y-276199D02*
Y-356199D01*
G01X534000Y167400D02*
X542850D01*
X546800Y163450D01*
G01X579811Y179500D02*
X574387D01*
X565787Y170900D01*
X556892D01*
X549442Y163450D01*
X546800D01*
G01X569500Y240225D02*
Y228738D01*
X573430Y224808D01*
X597608D01*
X600508Y227708D01*
X624440D01*
X625963Y226185D01*
Y225758D01*
X627363Y224358D01*
G01X637300Y234500D02*
Y229300D01*
X632590Y224590D01*
Y218800D01*
X618390Y204600D01*
X587100D01*
X582400Y209300D01*
G01D02*
Y209500D01*
G01X608800Y221400D02*
Y212900D01*
X607700Y211800D01*
G01X660146Y-276199D02*
Y-356199D01*
G01X775146Y-276199D02*
Y-356199D01*
G01X791300Y74200D02*
X807200D01*
X809000Y76000D01*
G01X942646Y-276199D02*
Y-356199D01*
G01X1112646Y-276199D02*
Y-356199D01*
G01X1269500Y397000D02*
X1265500D01*
X1259500Y391000D01*
X1250000D01*
X1249250Y390250D01*
G01X1269500Y397000D02*
X1272750Y393750D01*
X1309250D01*
G01X1310146Y-276199D02*
Y-356199D01*
G01X1342146Y-260199D02*
X1310146D01*
G01X1369300Y259300D02*
Y262800D01*
X1370900Y264400D01*
Y281300D01*
X1362700Y289500D01*
X1337500D01*
X1333400Y285400D01*
X1316578D01*
X1315078Y283900D01*
X1312100D01*
X1310500Y285500D01*
G01X1309250Y393750D02*
X1309584Y394084D01*
X1310068D01*
G01X1338146Y-260199D02*
G02I-12000J0D01*
G01X1332996D02*
G02I-6850J0D01*
G01X1326146Y-276199D02*
Y-244199D01*
X18577Y107902D03*
X5500Y119571D03*
Y139571D03*
Y159571D03*
Y179571D03*
Y199571D03*
Y219571D03*
Y239571D03*
X18000Y271600D03*
X5500Y259571D03*
X26600Y249217D03*
Y253582D03*
X18000Y289400D03*
X5500Y279571D03*
Y299571D03*
Y339571D03*
Y319571D03*
Y359571D03*
Y399571D03*
Y379571D03*
X25350Y389000D03*
X17500Y412374D03*
X5500Y419571D03*
Y439571D03*
Y479571D03*
Y459571D03*
Y499571D03*
Y519571D03*
Y539571D03*
X29300Y539850D03*
X5500Y579571D03*
Y559571D03*
Y599571D03*
Y639571D03*
Y619571D03*
Y679571D03*
Y659571D03*
Y699571D03*
X17500Y706300D03*
X5500Y719571D03*
Y739571D03*
X21250Y742650D03*
X5500Y779571D03*
Y759571D03*
Y799571D03*
X10020Y835051D03*
X30020D03*
X5500Y819571D03*
X35300Y303100D03*
X39000Y299500D03*
X31662Y303262D03*
X61800Y306900D03*
X38800Y302900D03*
X31700Y314700D03*
X62400Y342700D03*
X38518Y376916D03*
X34153D03*
X39866Y371366D03*
X35709Y426942D03*
X50140Y494559D03*
X60987Y489223D03*
X60150Y506450D03*
X61870Y515670D03*
X61128Y519646D03*
X61800Y537000D03*
X63000Y558930D03*
X62611Y608289D03*
X62400Y624500D03*
X63300Y634800D03*
X60700Y682100D03*
X63300Y697200D03*
X42130Y694440D03*
X50020Y835051D03*
X88259Y223184D03*
X92659D03*
X78000Y229289D03*
X73600D03*
X95700Y293900D03*
X66800Y342700D03*
X68365Y381464D03*
X96351Y443000D03*
Y438600D03*
X85042Y439144D03*
X91200Y448800D03*
Y453200D03*
X73232Y476912D03*
X97100Y466500D03*
X98400Y454400D03*
X70910Y502219D03*
X67700Y499120D03*
X77700Y522500D03*
X67700Y518500D03*
X67162Y515142D03*
X77300Y531238D03*
X77700Y538500D03*
X74301Y538390D03*
X65800Y538900D03*
X74300Y533600D03*
X77372Y526885D03*
X73700Y542600D03*
X70000Y542500D03*
X74000Y557000D03*
X87337Y569268D03*
X84226Y577924D03*
X87200Y565785D03*
X77400Y550400D03*
X65381Y548719D03*
X69100Y549200D03*
X73700Y549300D03*
X92000Y591200D03*
X69500Y586000D03*
X66000Y604800D03*
X94950Y677850D03*
X91450Y707650D03*
X65350Y690356D03*
X95400Y731600D03*
Y728200D03*
X70020Y835051D03*
X90020D03*
X118577Y107902D03*
X104000Y128330D03*
X114364Y122054D03*
X102499Y281183D03*
X111900Y344200D03*
X125600Y386700D03*
X107358Y409942D03*
X110406Y417067D03*
X113518Y420179D03*
X120000Y451285D03*
X107900Y448900D03*
X101200Y470400D03*
X129520Y448660D03*
X123696Y454452D03*
X114400Y550000D03*
X102870Y565740D03*
Y561340D03*
X128220Y620392D03*
X125581Y641436D03*
X124150Y707050D03*
X115000Y717600D03*
X107000Y717800D03*
X138577Y107902D03*
X158577D03*
X155026Y212580D03*
X155662Y266438D03*
X159662Y266600D03*
X162910Y244290D03*
X166087Y304350D03*
X134800Y329600D03*
X144595Y312861D03*
X155657Y384291D03*
X137000Y436700D03*
X145901Y441262D03*
X153100Y439000D03*
X136500Y417400D03*
X152978Y435602D03*
X137344Y446737D03*
X137000Y451300D03*
X163440Y453020D03*
X143547Y477976D03*
X159239Y449079D03*
X159082Y452509D03*
X153019Y622720D03*
X159716Y620392D03*
X166015D03*
X162100Y677800D03*
X160500Y689500D03*
X150000Y701500D03*
X142500Y709000D03*
X137000Y715500D03*
X150450Y744150D03*
X146450Y736150D03*
X135700Y745200D03*
X160700Y753400D03*
X139250Y791250D03*
X143250Y799250D03*
X153500Y808500D03*
X178577Y107902D03*
X167600Y247600D03*
X170062Y304556D03*
X167687Y329434D03*
X192407Y320262D03*
X180571Y327023D03*
X176674Y344934D03*
X189365Y329905D03*
X179381Y369903D03*
X196529Y352284D03*
X185970Y358962D03*
X195940Y348814D03*
X182969Y352641D03*
X166321Y388316D03*
X185000Y419900D03*
X199900Y544500D03*
X189500Y567700D03*
X193001Y574708D03*
X181000Y585000D03*
Y581500D03*
Y595200D03*
X168769Y622720D03*
X178750Y712250D03*
X184700Y729400D03*
X182750Y720250D03*
X193000Y729500D03*
X182750Y775750D03*
X178000Y753400D03*
X178750Y767750D03*
X177500Y784500D03*
X170800Y808500D03*
X193000Y785000D03*
X197420Y821701D03*
X197218Y871676D03*
X227669Y5500D03*
X210028Y12605D03*
Y32605D03*
Y52605D03*
Y72605D03*
X228163Y68589D03*
X210028Y92605D03*
X222354Y103006D03*
X228163Y78589D03*
X227606Y98642D03*
X223641Y99302D03*
X233500Y137000D03*
X210478Y151203D03*
X214794Y212100D03*
X205840Y325381D03*
X210177D03*
X221460Y335475D03*
Y339875D03*
X228100Y364600D03*
X219018Y378000D03*
X223383D03*
X217000Y360000D03*
X219580Y356970D03*
X214776Y352807D03*
X212536Y349805D03*
X205915Y422424D03*
X200100Y415100D03*
X202700Y495400D03*
X206700Y498000D03*
X200917Y490578D03*
X203550Y484522D03*
X233290Y493277D03*
X206700Y494000D03*
X203500Y499200D03*
X207026Y483956D03*
X226300Y505700D03*
X226530Y502307D03*
X216873Y516458D03*
X203300Y538500D03*
X206700Y544500D03*
Y538500D03*
X225000Y541300D03*
X219700Y550500D03*
X218780Y560082D03*
X206700Y548500D03*
X202300Y559763D03*
X229800Y558500D03*
X222500Y573220D03*
X227500Y603500D03*
X217000Y705500D03*
X210300Y729500D03*
X217000Y761000D03*
X210300Y785000D03*
X200620Y821701D03*
X225615Y875176D03*
X213017D03*
X200418Y871676D03*
X222415Y875176D03*
X209817D03*
X247669Y5500D03*
X257759Y68589D03*
X264817Y105350D03*
X257731Y78589D03*
X257912Y101408D03*
X258029Y97353D03*
X254000Y131500D03*
X244300Y226700D03*
X267300Y362200D03*
X244000Y377617D03*
Y381982D03*
X235750Y419500D03*
X251800Y470100D03*
X248500Y465000D03*
X263700Y474600D03*
X257493Y456679D03*
X253302D03*
X257400Y477300D03*
X244100Y499900D03*
X246800Y496800D03*
X257400Y481637D03*
X256300Y486000D03*
Y490000D03*
X242800Y495486D03*
X246500Y493400D03*
X240450Y499400D03*
X236737Y493170D03*
X239139Y525077D03*
X239321Y521081D03*
X264500Y521309D03*
X253500Y590500D03*
X257413D03*
X266100Y614400D03*
X265850Y606400D03*
X260100Y647400D03*
X259300Y632400D03*
Y639300D03*
X250500Y642500D03*
X265900Y622400D03*
X247717Y633233D03*
X259300Y635900D03*
X262628Y744470D03*
X260261Y875176D03*
X238213D03*
X257061D03*
X235013D03*
X267669Y5500D03*
X290000Y141100D03*
X274250Y133750D03*
X284440Y139580D03*
X285250Y133750D03*
X277800Y208500D03*
X283622Y226340D03*
X279257D03*
X282700Y300100D03*
X287200Y326802D03*
X267979Y342500D03*
X295400Y325390D03*
X283700Y322100D03*
X294009Y363063D03*
X293800Y436100D03*
X301170Y462780D03*
X301162Y459290D03*
X273783Y476100D03*
X283400Y477900D03*
X295876Y520800D03*
X296200Y566900D03*
X279994Y554794D03*
X283600Y551400D03*
X291000Y561450D03*
X280200Y551400D03*
X276300Y617350D03*
X281700Y634900D03*
X281100Y651700D03*
X270556Y716702D03*
X269500Y736150D03*
X286500Y740500D03*
X285500Y866200D03*
X272859Y875176D03*
X282300Y866200D03*
X269659Y875176D03*
X306900Y251000D03*
X302500Y251600D03*
X311882Y310550D03*
X307425Y309838D03*
X303517Y309777D03*
X313200Y299900D03*
X310485Y314670D03*
X328800Y315900D03*
X315900Y320900D03*
X313100Y371038D03*
Y374438D03*
X301320Y362500D03*
X313500Y437400D03*
Y441000D03*
X313300Y429603D03*
X313294Y434006D03*
X306521Y463576D03*
X304293Y466146D03*
X329014Y472022D03*
X322268Y466591D03*
X322305Y469991D03*
X321900Y459800D03*
X322036Y463198D03*
X327512Y509612D03*
X303800Y505100D03*
X304400Y511400D03*
X327589Y504300D03*
X333102Y485902D03*
X330000Y501900D03*
X322700Y536500D03*
X311500Y548000D03*
X314900D03*
X322100Y638500D03*
X309000Y679000D03*
X305500Y676400D03*
X334800Y712000D03*
X317300Y739300D03*
X302000Y740800D03*
X320000Y718200D03*
X323600Y717800D03*
X323253Y875176D03*
X310955Y865676D03*
X332651Y875176D03*
X320053D03*
X307755Y865676D03*
X362528Y123931D03*
X358917Y124122D03*
X355069D03*
X352600Y128200D03*
Y132537D03*
X341652Y305034D03*
Y301534D03*
X362500Y341700D03*
X362825Y336000D03*
X356953Y353653D03*
X359403Y351203D03*
X352003Y358603D03*
X354505Y356102D03*
X360820Y359299D03*
X363270Y356940D03*
X355872Y363965D03*
X358362Y361649D03*
X335570Y491460D03*
X342300Y511600D03*
X350000Y537600D03*
X347100Y605300D03*
X357600Y638300D03*
X354300Y696000D03*
Y704500D03*
X367675Y723000D03*
X361048Y875176D03*
X348450D03*
X335851D03*
X357848D03*
X345250D03*
X387669Y5500D03*
X401300Y156715D03*
Y153215D03*
X383600Y203200D03*
X376600Y261350D03*
X381700Y265800D03*
X368900Y315700D03*
X370700Y353900D03*
X395100Y449100D03*
X380300Y508700D03*
X401000Y575500D03*
X372000Y579300D03*
X388900Y550400D03*
X386500Y607900D03*
X370875Y723000D03*
X395694Y875176D03*
X383096D03*
X392494D03*
X379896D03*
X407669Y5500D03*
X427669D03*
X403600Y142542D03*
X435161Y166892D03*
X403600Y146042D03*
X422876Y199830D03*
Y204195D03*
X433400Y176800D03*
X410900Y217100D03*
X404040Y318900D03*
Y323300D03*
X416100Y470800D03*
X418900Y529300D03*
X420891Y875176D03*
X408292D03*
X417691D03*
X405092D03*
X447669Y5500D03*
X467669D03*
X465127Y57727D03*
X438561Y166892D03*
X456500Y169783D03*
Y165418D03*
X448200Y531400D03*
X469000Y784000D03*
X456335Y835051D03*
X444500Y864450D03*
X489261Y-14185D03*
X496782Y134315D03*
X474990Y122660D03*
X498000Y194200D03*
X477037Y333841D03*
X473637Y333876D03*
X500198Y324041D03*
X480532Y321332D03*
X480000Y355800D03*
X476600D03*
X487000Y393300D03*
X480368Y405606D03*
X476531D03*
X472600Y477700D03*
X487400Y492100D03*
X478000Y777500D03*
X483850Y773800D03*
X483000Y788150D03*
X499000Y793000D03*
X485300Y811750D03*
X496335Y835051D03*
X477206Y820648D03*
X500700Y828100D03*
X509369Y141559D03*
X530800Y123900D03*
X534000Y167400D03*
X518686Y163800D03*
Y168200D03*
X510462Y261315D03*
X529126Y342336D03*
X532978Y371023D03*
X528850Y394750D03*
X518100Y453200D03*
X515900Y768300D03*
X531500Y774500D03*
X531600Y770200D03*
X519748Y768297D03*
X515650Y764500D03*
X519906Y764900D03*
X532000Y792500D03*
X515000D03*
X527500Y836200D03*
X527941Y864680D03*
X546800Y163450D03*
X547173Y167987D03*
X569500Y240225D03*
X541681Y297976D03*
X539400Y376444D03*
X561300Y369500D03*
X539400Y380781D03*
X559973Y387638D03*
X561912Y390762D03*
X567150Y415750D03*
X560900Y413700D03*
X544000Y761000D03*
X540500Y781000D03*
X547395Y761198D03*
X540500Y761000D03*
X567348Y875176D03*
X554750D03*
X542151D03*
X564148D03*
X551550D03*
X538951D03*
X579811Y179500D03*
X582400Y209500D03*
X597600Y339100D03*
X604400Y421200D03*
X579900Y427400D03*
X592545Y875176D03*
X579947D03*
X601944D03*
X589345D03*
X576747D03*
X607700Y211800D03*
X608800Y221400D03*
X635863Y216308D03*
X635190Y219641D03*
X627363Y224358D03*
X637300Y234500D03*
X615500Y420100D03*
X619100Y418000D03*
X630340Y875176D03*
X617742D03*
X605144D03*
X627140D03*
X614542D03*
X649400Y234500D03*
X642463Y241608D03*
X664986Y875176D03*
X652388D03*
X661786D03*
X649188D03*
X697494Y186256D03*
Y181919D03*
X693300Y181200D03*
X680100Y378718D03*
X683600D03*
X702400Y868800D03*
X690183Y875176D03*
X677585D03*
X699200Y868800D03*
X686983Y875176D03*
X674385D03*
X728395Y-7315D03*
X713461Y-3006D03*
X729132Y3575D03*
X722955Y33095D03*
X726155D03*
X726609Y49251D03*
Y46051D03*
X734277Y875176D03*
X731077D03*
X746329Y-7789D03*
X772073Y875176D03*
X759474D03*
X746876D03*
X768873D03*
X756274D03*
X743676D03*
X790150Y-1400D03*
X788408Y-4321D03*
X791300Y74200D03*
X792760Y176043D03*
X799000Y196000D03*
X802200D03*
X792000Y195778D03*
X787600Y195804D03*
X792760Y180443D03*
X778807Y183890D03*
Y179490D03*
X797270Y875176D03*
X784671D03*
X806668D03*
X794070D03*
X781471D03*
X809000Y76000D03*
X840500Y735500D03*
X837000D03*
X835065Y875176D03*
X809868D03*
X831865D03*
X861000Y350D03*
X857453Y303D03*
X863300Y23575D03*
X868200Y116000D03*
X846702Y117371D03*
X854400Y117500D03*
X861300Y117800D03*
X851500Y705500D03*
X852500Y718000D03*
X847500Y717500D03*
X852895Y748648D03*
X869406Y745531D03*
X848000Y735500D03*
X865406Y745598D03*
X873367Y745335D03*
X844000Y735500D03*
X858126Y763600D03*
X841500Y771000D03*
X874000Y772000D03*
X853500Y798000D03*
X846706Y797648D03*
X874570Y811820D03*
X861823Y853696D03*
X847663Y875176D03*
X844463D03*
X883800Y-500D03*
X881700Y2300D03*
X883800Y41400D03*
X885400Y743600D03*
X893400Y745100D03*
X877000Y745000D03*
X889900Y769600D03*
X876470Y808710D03*
X906396Y810300D03*
X881720Y807390D03*
X906450Y806900D03*
X906092Y813687D03*
X884412Y835051D03*
X939064Y58104D03*
X934881Y57322D03*
X938898Y640169D03*
X916319Y678588D03*
Y658588D03*
Y698588D03*
Y738588D03*
Y718588D03*
Y778588D03*
Y758588D03*
Y798588D03*
Y818588D03*
X970064Y18764D03*
X963700Y21700D03*
X959877Y26978D03*
X964105Y62308D03*
X959855Y61107D03*
X957800Y570300D03*
X958898Y640169D03*
X1008353Y-1940D03*
X1006100Y528700D03*
X977500Y550000D03*
X978898Y640169D03*
X994248Y665818D03*
Y685818D03*
Y705818D03*
Y745818D03*
Y725818D03*
Y765818D03*
Y805818D03*
Y785818D03*
X1012177Y-2940D03*
X1019859Y-7642D03*
X1030139Y30209D03*
X1019900Y108500D03*
X1015948D03*
X1034500D03*
X1027483Y108431D03*
X1024000Y108500D03*
X1037900D03*
X1041300D03*
X1030883Y108438D03*
X1012600Y476700D03*
X1022600Y542100D03*
X1017800Y572700D03*
X1043300Y631300D03*
X1041500Y682000D03*
X1041900Y658100D03*
X1024004Y855893D03*
X1038214Y875176D03*
X1035014D03*
X1069261Y-14185D03*
X1049261D03*
X1045850Y6228D03*
X1069200Y-4200D03*
X1072804Y19894D03*
X1064900Y10400D03*
X1065700Y32888D03*
Y36088D03*
X1061200Y20888D03*
Y24088D03*
X1076970Y30411D03*
X1052600Y14400D03*
X1048100Y108500D03*
X1044700D03*
X1047000Y644000D03*
X1045000Y617500D03*
X1076010Y875176D03*
X1050813D03*
X1072810D03*
X1047613D03*
X1089261Y-14185D03*
X1082974Y14467D03*
X1103300Y73900D03*
X1103349Y70700D03*
X1101207Y875176D03*
X1088608D03*
X1110605D03*
X1098007D03*
X1085408D03*
X1112700Y80700D03*
X1114842Y83078D03*
X1143000Y242000D03*
X1139002Y875176D03*
X1126403D03*
X1113805D03*
X1135802D03*
X1123203D03*
X1147000Y242000D03*
X1151000D03*
X1164199Y875176D03*
X1151600D03*
X1160999D03*
X1148400D03*
X1199000Y867200D03*
X1186246Y875176D03*
X1195800Y867300D03*
X1183046Y875176D03*
X1242939D03*
X1230340D03*
X1239739D03*
X1227140D03*
X1249250Y390250D03*
X1269500Y397000D03*
X1268136Y875176D03*
X1255537D03*
X1277534D03*
X1264936D03*
X1252337D03*
X1303983Y22083D03*
X1304000Y44000D03*
Y67500D03*
Y90500D03*
X1310500Y285500D03*
X1282740Y350010D03*
X1293280Y345770D03*
X1289960Y349900D03*
X1299000Y347500D03*
X1311500Y391000D03*
X1310068Y394084D03*
X1289500Y386500D03*
X1282740Y383000D03*
X1282000Y386500D03*
X1297617Y677117D03*
X1304500Y698000D03*
X1291428Y726117D03*
X1305931Y875176D03*
X1293333D03*
X1280734D03*
X1302731D03*
X1290133D03*
X1339471Y139268D03*
X1316590Y147210D03*
X1317400Y143620D03*
X1340130Y145980D03*
X1331243Y182198D03*
X1322000Y276500D03*
X1331000Y662000D03*
X1334128Y674000D03*
X1337500Y698000D03*
X1322439Y697767D03*
X1336795Y685141D03*
X1343726Y875176D03*
X1331128D03*
X1318529D03*
X1340526D03*
X1327928D03*
X1315329D03*
X1359128Y167226D03*
X1355321Y172119D03*
X1354971Y167446D03*
X1369300Y259300D03*
X1364000Y280500D03*
X1351500Y675000D03*
X1369925Y835051D03*
X1357886Y864246D03*
X1394500Y139626D03*
Y119626D03*
Y159626D03*
Y199626D03*
Y179626D03*
Y239626D03*
Y219626D03*
Y259626D03*
Y299626D03*
Y279626D03*
Y339626D03*
Y319626D03*
Y359626D03*
Y399626D03*
Y379626D03*
Y439626D03*
Y419626D03*
Y479626D03*
Y459626D03*
Y499626D03*
Y539626D03*
Y519626D03*
Y579626D03*
Y559626D03*
Y599626D03*
Y639626D03*
Y619626D03*
Y679626D03*
Y659626D03*
Y699626D03*
Y739626D03*
Y719626D03*
Y759626D03*
Y779626D03*
Y799626D03*
Y819626D03*
X1389925Y835051D03*
G54D20*
G01X87337Y569268D02*
X89550Y567055D01*
Y565543D01*
X96213Y558880D01*
Y554057D01*
X107370Y542900D01*
X122506D01*
X124822Y545216D01*
G01X87200Y565785D02*
X87184D01*
Y565736D01*
X87200Y565720D01*
Y564923D01*
X94113Y558010D01*
Y553187D01*
X106300Y541000D01*
X122739D01*
X124822Y538917D01*
G01Y545216D02*
X127905D01*
X131122Y541999D01*
Y532618D01*
G01X127973Y538918D02*
X124823Y535768D01*
Y535766D01*
G01X114400Y550000D02*
X116939Y547461D01*
X134926D01*
X139471Y542916D01*
Y539913D01*
X143721Y535663D01*
Y532618D01*
G01X153168Y529469D02*
X151118Y527419D01*
X142619D01*
X140569Y529469D01*
G54D11*
X130985Y504300D03*
X118500Y504238D03*
X115373Y504271D03*
X131121Y513721D03*
Y510570D03*
X127971Y494823D03*
X131121D03*
X124823Y523170D03*
X124822Y545216D03*
X131122Y532618D03*
X124823Y535766D03*
X127973Y538918D03*
X121673Y523170D03*
X124822Y538917D03*
X121922Y588872D03*
X118773Y592048D03*
X125072Y620392D03*
X121921D03*
X140571Y491674D03*
X162618Y485374D03*
X150020Y491674D03*
X143721D03*
Y488524D03*
Y485374D03*
X153170Y491674D03*
X137421D03*
X156319D03*
X159469D03*
X150020Y488524D03*
X165766Y542066D03*
X143721Y532618D03*
X153168Y529469D03*
X140569D03*
X134272Y532618D03*
X153418Y592048D03*
X159716D03*
X134521Y598345D03*
X143968Y592048D03*
X147117Y601495D03*
X137671Y617266D03*
X140821D03*
X156566Y617244D03*
X159716D03*
X150351Y620436D03*
X181514Y479075D03*
X172065Y513721D03*
Y510571D03*
Y501122D03*
Y491674D03*
X184664Y485372D03*
X172065Y494823D03*
X184664Y488522D03*
X175215Y494823D03*
X172065Y504272D03*
X175216Y504271D03*
X172065Y507422D03*
X178365Y504272D03*
Y520020D03*
X172065Y535768D03*
Y526319D03*
X178365Y529469D03*
X172065D03*
X168916Y523170D03*
X901969Y139764D03*
Y131890D03*
X886221Y139764D03*
X890158Y135827D03*
X886221Y131890D03*
X890158Y139764D03*
X894095Y135827D03*
X890158Y131890D03*
Y159449D03*
X886221Y155512D03*
X890158Y151575D03*
X886221Y147638D03*
X890158Y143701D03*
X894095Y159449D03*
X890158Y155512D03*
X894095Y151575D03*
X890158Y147638D03*
X894095Y143701D03*
X901969Y155512D03*
X898032Y194881D03*
Y198818D03*
Y202755D03*
X894095D03*
X898032Y179134D03*
Y183071D03*
Y190944D03*
X905906Y183071D03*
X901969D03*
X886221Y206692D03*
X890158Y198818D03*
X886221Y194881D03*
X890158Y190944D03*
X886221Y183071D03*
X890158Y206692D03*
X894095Y198818D03*
X890158Y194881D03*
X894095Y190944D03*
X890158Y183071D03*
X898032Y238188D03*
X894095D03*
X898032Y234251D03*
Y230314D03*
X905906Y238188D03*
X901969D03*
X898032Y226377D03*
Y222440D03*
Y218503D03*
Y214566D03*
Y210629D03*
X890158Y234251D03*
X886221Y230314D03*
X890158Y226377D03*
X886221Y222440D03*
X890158Y218503D03*
X886221Y214566D03*
X890158Y210629D03*
X905906Y242125D03*
X898032D03*
X890158D03*
X882284D03*
X894095Y234251D03*
X890158Y230314D03*
X894095Y226377D03*
X890158Y222440D03*
X894095Y218503D03*
X890158Y214566D03*
X894095Y210629D03*
X905906Y246062D03*
X901969Y249999D03*
X898032Y246062D03*
X894095Y249999D03*
X890158Y246062D03*
X886221Y249999D03*
X882284Y246062D03*
X878347Y249999D03*
X901969Y246062D03*
X894095D03*
X886221D03*
X878347D03*
X933465Y131890D03*
Y135827D03*
X937402Y131890D03*
Y135827D03*
X929528Y131890D03*
Y135827D03*
X925591Y131890D03*
Y135827D03*
X909843Y120079D03*
X913780Y116142D03*
X917717Y120079D03*
X921654Y116142D03*
X925591Y120079D03*
X929528Y116142D03*
X933465Y120079D03*
X937402Y116142D03*
X909843Y124016D03*
X913780Y120079D03*
X917717Y124016D03*
X921654Y120079D03*
X925591Y124016D03*
X929528Y120079D03*
X933465Y124016D03*
X937402Y120079D03*
X929528Y159449D03*
X913780Y143701D03*
X937402Y159449D03*
X933465Y143701D03*
Y147638D03*
X937402Y143701D03*
Y147638D03*
X929528Y143701D03*
Y147638D03*
X917717Y179134D03*
X921654Y238188D03*
X917717D03*
Y214566D03*
X913780Y238188D03*
X909843D03*
X941339Y242125D03*
X933465D03*
X925591D03*
X917717D03*
X941339Y246062D03*
X937402Y249999D03*
X933465Y246062D03*
X929528Y249999D03*
X925591Y246062D03*
X921654Y249999D03*
X917717Y246062D03*
X913780Y249999D03*
X937402Y246062D03*
X929528D03*
X921654D03*
X913780D03*
X957086Y127953D03*
X964960D03*
X972834D03*
X957086Y139764D03*
X972834D03*
X957086Y116142D03*
X961023Y120079D03*
X964960Y116142D03*
X968897Y120079D03*
X972834Y116142D03*
X957086Y120079D03*
X961023Y124016D03*
X964960Y120079D03*
X968897Y124016D03*
X972834Y120079D03*
X968897Y135827D03*
Y151575D03*
X964960Y159449D03*
X957086D03*
X972834Y151575D03*
X949212Y143701D03*
Y147638D03*
X968897D03*
X972834Y238188D03*
X968897Y242125D03*
X961023D03*
X953149D03*
X972834Y249999D03*
X968897Y246062D03*
X964960Y249999D03*
X961023Y246062D03*
X957086Y249999D03*
X953149Y246062D03*
X972834D03*
X964960D03*
X957086D03*
X980708Y127953D03*
Y131890D03*
X1008267Y139764D03*
X976771Y120079D03*
X980708Y116142D03*
X984645Y120079D03*
X1008267Y131890D03*
X1004330Y135827D03*
Y139764D03*
X976771Y124016D03*
X980708Y120079D03*
X984645Y124016D03*
X1004330Y131890D03*
X1000393Y135827D03*
X976771D03*
X996456Y163386D03*
X1000393D03*
X996456Y167323D03*
Y171260D03*
Y175197D03*
X992519Y163386D03*
X988582D03*
X980708Y175197D03*
X996456Y143701D03*
Y147638D03*
Y151575D03*
Y155512D03*
Y159449D03*
X976771Y151575D03*
X1004330Y143701D03*
X1008267Y147638D03*
X1004330Y151575D03*
X1008267Y155512D03*
X1004330Y159449D03*
X1008267Y167323D03*
X1004330Y171260D03*
X1008267Y175197D03*
X1000393Y143701D03*
X1004330Y147638D03*
X1000393Y151575D03*
X1004330Y155512D03*
X1000393Y159449D03*
X1004330Y167323D03*
X1000393Y171260D03*
X1004330Y175197D03*
X984645Y155512D03*
Y143701D03*
X976771Y147638D03*
X996456Y194881D03*
Y198818D03*
Y202755D03*
X1000393D03*
X996456Y179134D03*
Y183071D03*
Y190944D03*
X992519Y183071D03*
X988582D03*
X976771Y179134D03*
X1004330D03*
X1008267Y183071D03*
X1004330Y190944D03*
X1008267Y194881D03*
X1004330Y198818D03*
X1008267Y206692D03*
X1000393Y179134D03*
X1004330Y183071D03*
X1000393Y190944D03*
X1004330Y194881D03*
X1000393Y198818D03*
X1004330Y206692D03*
X992519Y238188D03*
X988582D03*
X984645D03*
X980708D03*
X1000393D03*
X996456D03*
Y234251D03*
Y230314D03*
Y226377D03*
Y222440D03*
Y218503D03*
Y214566D03*
Y210629D03*
X976771Y238188D03*
Y214566D03*
X1004330Y210629D03*
X1008267Y214566D03*
X1004330Y218503D03*
X1008267Y222440D03*
X1004330Y226377D03*
X1008267Y230314D03*
X1004330Y234251D03*
X1000393Y210629D03*
X1004330Y214566D03*
X1000393Y218503D03*
X1004330Y222440D03*
X1000393Y226377D03*
X1004330Y230314D03*
X1000393Y234251D03*
X1004330Y242125D03*
X996456D03*
X988582D03*
X976771D03*
X1008267Y249999D03*
X1004330Y246062D03*
X1000393Y249999D03*
X996456Y246062D03*
X992519Y249999D03*
X988582Y246062D03*
X980708Y249999D03*
X976771Y246062D03*
X1008267D03*
X1000393D03*
X992519D03*
X980708D03*
X1012204Y242125D03*
X1016141Y249999D03*
X1012204Y246062D03*
X1016141D03*
G54D21*
G01X597600Y339100D02*
X554600Y296100D01*
Y261000D01*
X544100Y250500D01*
X521277D01*
X510462Y261315D01*
G54D12*
X183900Y274372D03*
X302500Y207200D03*
X762300Y16200D03*
G54D22*
G01X216873Y516458D02*
X216831Y516500D01*
X190900D01*
X189119Y514719D01*
X183666D01*
X178365Y520020D01*
G54D13*
X239900Y600100D03*
X240000Y608600D03*
Y604400D03*
X536081Y304376D03*
X536809Y298789D03*
X557904Y327115D03*
G54D23*
G01X88259Y223184D02*
X89859Y224784D01*
Y228892D01*
X91314Y230347D01*
X94934D01*
X105867Y219414D01*
X141609D01*
X201500Y159523D01*
Y132400D01*
X219084Y114816D01*
Y98791D01*
X226175Y91700D01*
X236645D01*
X243547Y84798D01*
Y78989D01*
X243947Y78589D01*
X257731D01*
G01X228163D02*
X241947D01*
X242347Y78989D01*
Y84300D01*
X236147Y90500D01*
X225677D01*
X217884Y98293D01*
Y114318D01*
X200300Y131902D01*
Y145400D01*
X199550Y146150D01*
Y147350D01*
X200300Y148100D01*
Y149300D01*
X199550Y150050D01*
Y151250D01*
X200300Y152000D01*
Y159025D01*
X190782Y168543D01*
X189722D01*
X188873Y169391D01*
Y170452D01*
X188024Y171301D01*
X186964D01*
X186115Y172149D01*
Y173210D01*
X185267Y174058D01*
X184206D01*
X183358Y174907D01*
Y175967D01*
X182509Y176816D01*
X181448D01*
X180600Y177664D01*
Y178725D01*
X141111Y218214D01*
X105369D01*
X94436Y229147D01*
X91812D01*
X91059Y228394D01*
Y224784D01*
X92659Y223184D01*
G01X78000Y229289D02*
X76400Y227689D01*
Y225500D01*
X86538Y215362D01*
X136896D01*
X170080Y182178D01*
Y179450D01*
X195300Y154230D01*
Y130794D01*
X214900Y111194D01*
Y87174D01*
X225887Y76187D01*
X238846D01*
X243561Y71472D01*
Y68989D01*
X243961Y68589D01*
X257759D01*
G01X73600Y229289D02*
X75200Y227689D01*
Y225002D01*
X86040Y214162D01*
X136398D01*
X168880Y181680D01*
Y178952D01*
X194100Y153732D01*
Y130296D01*
X213700Y110696D01*
Y86676D01*
X225389Y74987D01*
X238348D01*
X242361Y70974D01*
Y68989D01*
X241961Y68589D01*
X228163D01*
G01X877800Y168650D02*
X877900D01*
X878150Y168900D01*
X918334D01*
X919267Y167967D01*
Y134361D01*
X920172Y133458D01*
X923223D01*
X924337Y133128D01*
G02X924462Y133017I-934J-1178D01*
G01X924463D01*
Y133016D01*
X925591Y131890D01*
G01X877606Y169950D02*
X877656D01*
X877906Y169700D01*
X918666D01*
X920067Y168299D01*
Y134693D01*
X920503Y134258D01*
X923340D01*
X924613Y133882D01*
Y133881D01*
G03X926033Y134198I434J1394D01*
G03X926058Y135360I-543J593D01*
G01X925591Y135827D01*
G01X871857Y176357D02*
X872247Y176747D01*
X926246D01*
G02X926599Y176601I0J-500D01*
G01X926995Y176205D01*
G02X927141Y175852I-354J-353D01*
G01Y142966D01*
G03X927520Y142047I1300J-1D01*
G01X927837Y141730D01*
G03X928756Y141351I918J921D01*
G01X930051D01*
G02X930334Y141234I0J-401D01*
G01X930961Y140607D01*
G02X931078Y140324I-284J-283D01*
G01Y139323D01*
G03X931428Y138474I1201J-1D01*
G01X932138Y137765D01*
X932139D01*
X932344Y137560D01*
G03X932697Y137414I353J354D01*
G01X934379D01*
G02X934732Y137268I0J-500D01*
G01X934870Y137130D01*
G02X935016Y136777I-354J-353D01*
G01Y134752D01*
G03X935385Y133854I1274J-1D01*
G01X935390Y133849D01*
X935391D01*
G03X936284Y133479I893J893D01*
G01X936611D01*
G02X936730Y133469I-6J-789D01*
G02X936732I1J-789D01*
G02X937169Y133248I-120J-780D01*
G01X937170Y133247D01*
G02X937402Y132687I-560J-560D01*
G01Y131890D01*
G01X890158Y183071D02*
G02X889923Y182502I-804J-1D01*
G01X889363Y181943D01*
X888602Y181182D01*
G02X888322Y180956I-1201J1202D01*
G02X887400Y180684I-922J1427D01*
G01X885199D01*
G03X883900Y180146I0J-1837D01*
G01X871318Y177657D02*
X871428Y177547D01*
X926246D01*
G02X927165Y177168I1J-1300D01*
G01X927562Y176771D01*
G02X927941Y175852I-921J-918D01*
G01Y142966D01*
G03X928087Y142613I500J0D01*
G01X928403Y142297D01*
G03X928756Y142151I353J354D01*
G01X930342D01*
G02X930695Y142005I0J-500D01*
G01X931732Y140968D01*
G02X931878Y140615I-354J-353D01*
G01Y139323D01*
G03X931995Y139040I401J0D01*
G01X932705Y138331D01*
G03X932988Y138214I283J284D01*
G01X934379D01*
G02X935298Y137835I1J-1300D01*
G01X935437Y137696D01*
G02X935816Y136777I-921J-918D01*
G01Y134752D01*
G03X935954Y134418I473J0D01*
G03X936290Y134279I336J337D01*
G01X936859D01*
G03X937600Y134700I0J863D01*
G03X937402Y135827I-752J449D01*
G01X886221Y183071D02*
Y183121D01*
X887029Y183929D01*
G02X887700Y184207I671J-671D01*
G02X888200Y184000I0J-707D01*
G01X888300Y183900D01*
G02X888608Y183156I-744J-744D01*
G01Y182696D01*
G02X888343Y182056I-905J0D01*
G01X888036Y181748D01*
G02X887887Y181629I-632J639D01*
G02X887400Y181484I-489J753D01*
G01X884038D01*
X884000Y181446D01*
G01X890158Y194881D02*
G02X889923Y194312I-804J-1D01*
G01X889205Y193595D01*
X888602Y192992D01*
G02X888322Y192766I-1201J1202D01*
G02X887400Y192494I-922J1427D01*
G01X871538D01*
X871444Y192400D01*
G01X886221Y194881D02*
G02X886971Y195631I750J0D01*
G01X887720D01*
G02X888314Y195385I0J-840D01*
G01X888332Y195368D01*
G02X888608Y194700I-668J-667D01*
G01Y194510D01*
G02X888586Y194311I-918J1D01*
G02X888339Y193861I-896J199D01*
G01X888089Y193611D01*
G02X887324Y193294I-765J765D01*
G01X872206D01*
X871800Y193700D01*
G01X886221Y206692D02*
G02X886971Y207442I750J0D01*
G01X887720D01*
G02X888314Y207196I0J-840D01*
G01X888332Y207179D01*
G02X888608Y206511I-668J-667D01*
G01Y206321D01*
G02X888586Y206122I-918J1D01*
G02X888339Y205672I-896J199D01*
G01X888089Y205422D01*
G02X887324Y205105I-765J765D01*
G01X872812D01*
G02X872100Y205400I0J1007D01*
G01X872900Y197500D02*
G03X873549Y197231I649J649D01*
G01X891261D01*
G03X892026Y197548I0J1082D01*
G01X892276Y197798D01*
G03X892545Y198447I-649J649D01*
G01Y198637D01*
G03X892269Y199305I-944J1D01*
G01X892251Y199322D01*
G03X891657Y199568I-594J-594D01*
G01X890908D01*
G03X890158Y198818I0J-750D01*
G01Y206692D02*
G02X889923Y206123I-804J-1D01*
G01X889205Y205406D01*
X888602Y204803D01*
G02X888322Y204577I-1201J1202D01*
G02X887400Y204305I-922J1427D01*
G01X872595D01*
G03X872100Y204100I0J-700D01*
G01X894095Y198818D02*
G02X893860Y198249I-804J-1D01*
G01X892539Y196929D01*
G02X892259Y196703I-1201J1202D01*
G02X891337Y196431I-922J1427D01*
G01X873164D01*
G03X872606Y196200I0J-789D01*
G01X873000Y209300D02*
G03X873623Y209042I623J623D01*
G01X891261D01*
G03X892026Y209359I0J1082D01*
G01X892276Y209609D01*
G03X892523Y210059I-649J649D01*
G03X892545Y210258I-896J200D01*
G01Y210448D01*
G03X892269Y211116I-944J1D01*
G01X892251Y211133D01*
G03X891657Y211379I-594J-594D01*
G01X890908D01*
G03X890158Y210629I0J-750D01*
G01X873000Y208000D02*
G02X873584Y208242I584J-584D01*
G01X891337D01*
G03X892259Y208514I0J1699D01*
G03X892539Y208740I-921J1428D01*
G01X893142Y209343D01*
X893860Y210060D01*
G03X894095Y210629I-569J568D01*
G01X872300Y213300D02*
G03X873075Y212979I775J775D01*
G01X887348D01*
G03X888072Y213279I0J1024D01*
G01X888339Y213546D01*
G03X888608Y214195I-649J649D01*
G01Y214385D01*
G03X888332Y215053I-944J1D01*
G01X888314Y215070D01*
G03X887720Y215316I-594J-594D01*
G01X886971D01*
G03X886221Y214566I0J-750D01*
G01X872300Y212000D02*
G02X872732Y212179I432J-432D01*
G01X887400D01*
G03X888322Y212451I0J1699D01*
G03X888602Y212677I-921J1428D01*
G01X889923Y213997D01*
G03X890158Y214566I-569J568D01*
G01X873300Y217100D02*
G03X873744Y216916I444J444D01*
G01X891261D01*
G03X892026Y217233I0J1082D01*
G01X892276Y217483D01*
G03X892545Y218132I-649J649D01*
G01Y218322D01*
G03X892269Y218990I-944J1D01*
G01X892251Y219007D01*
G03X891657Y219253I-594J-594D01*
G01X890908D01*
G03X890158Y218503I0J-750D01*
G01X873300Y215800D02*
G02X874063Y216116I763J-763D01*
G01X891337D01*
G03X892259Y216388I0J1699D01*
G03X892539Y216614I-921J1428D01*
G01X893860Y217934D01*
G03X894095Y218503I-569J568D01*
G01X872400Y221100D02*
G03X872996Y220853I596J596D01*
G01X887324D01*
G03X888089Y221170I0J1082D01*
G01X888339Y221420D01*
G03X888608Y222069I-649J649D01*
G01Y222259D01*
G03X888332Y222927I-944J1D01*
G01X888314Y222944D01*
G03X887720Y223190I-594J-594D01*
G01X886971D01*
G03X886221Y222440I0J-750D01*
G01X871600Y219800D02*
G02X873011Y220053I1411J-3808D01*
G01X887400D01*
G03X888322Y220325I0J1699D01*
G03X888602Y220551I-921J1428D01*
G01X889923Y221871D01*
G03X890158Y222440I-569J568D01*
G01X894095Y226377D02*
G02X893860Y225808I-804J-1D01*
G01X892539Y224488D01*
G02X892259Y224262I-1201J1202D01*
G02X891337Y223990I-922J1427D01*
G01X873390D01*
X873300Y223900D01*
G01X873285Y229054D02*
G03X874074Y228727I789J789D01*
G01X887348D01*
G03X888072Y229027I0J1024D01*
G01X888339Y229294D01*
G03X888608Y229943I-649J649D01*
G01Y230133D01*
G03X888332Y230801I-944J1D01*
G01X888314Y230818D01*
G03X887720Y231064I-594J-594D01*
G01X886971D01*
G03X886221Y230314I0J-750D01*
G01X890158Y226377D02*
G02X890908Y227127I750J0D01*
G01X891657D01*
G02X892251Y226881I0J-840D01*
G01X892269Y226864D01*
G02X892545Y226196I-668J-667D01*
G01Y226006D01*
G02X892276Y225357I-918J0D01*
G01X892026Y225107D01*
G02X891261Y224790I-765J765D01*
G01X874284D01*
G02X873304Y225196I0J1386D01*
G01X873300Y225200D01*
G01X871846Y228653D02*
G03X873599Y227927I1753J1753D01*
G01X887400D01*
G03X888322Y228199I0J1699D01*
G03X888602Y228425I-921J1428D01*
G01X889923Y229745D01*
G03X890158Y230314I-569J568D01*
G01X894095Y234251D02*
G02X893860Y233682I-804J-1D01*
G01X892539Y232362D01*
G02X892259Y232136I-1201J1202D01*
G02X891337Y231864I-922J1427D01*
G01X875304D01*
G02X874780Y232081I0J741D01*
G01X875700Y233000D02*
X875708Y232992D01*
G03X876500Y232664I792J792D01*
G01X891261D01*
G03X892026Y232981I0J1082D01*
G01X892276Y233231D01*
G03X892545Y233880I-649J649D01*
G01Y234070D01*
G03X892269Y234738I-944J1D01*
G01X892251Y234755D01*
G03X891657Y235001I-594J-594D01*
G01X890908D01*
G03X890158Y234251I0J-750D01*
G01X933465Y131890D02*
Y132687D01*
G03X933233Y133247I-792J0D01*
G01X933232Y133248D01*
G03X932822Y133464I-557J-559D01*
G03X932674Y133479I-153J-774D01*
G01X932347D01*
G02X931454Y133849I0J1263D01*
G01X931453D01*
X931448Y133854D01*
G02X931079Y134752I905J897D01*
G01X931078Y134753D01*
Y136490D01*
X930191Y137377D01*
X924730D01*
G02X923811Y137756I-1J1300D01*
G01X923620Y137947D01*
G02X923241Y138866I921J918D01*
G01Y172252D01*
G03X923095Y172605I-500J0D01*
G01X922999Y172701D01*
G03X922646Y172847I-353J-354D01*
G01X878854D01*
G03X878501Y172701I0J-500D01*
G01X878300Y172500D01*
G01Y173800D02*
X878448D01*
Y173647D01*
X922646D01*
G02X923565Y173268I1J-1300D01*
G01X923662Y173171D01*
G02X924041Y172252I-921J-918D01*
G01Y138866D01*
G03X924187Y138513I500J0D01*
G01X924377Y138323D01*
G03X924730Y138177I353J354D01*
G01X930316D01*
G02X930669Y138031I0J-500D01*
G01X931732Y136968D01*
G02X931878Y136615I-354J-353D01*
G01Y136307D01*
X931879Y136306D01*
Y134752D01*
G03X932017Y134418I473J0D01*
G03X932353Y134279I336J337D01*
G01X933079D01*
G03X933600Y134800I0J521D01*
G01Y135501D01*
G03X933465Y135827I-461J0D01*
G01X880998Y263197D02*
X880999Y263097D01*
X880697Y263035D01*
Y245284D01*
G03X881008Y244533I1062J0D01*
G01X881013Y244529D01*
G03X881726Y244233I714J713D01*
G01X881926D01*
G03X882493Y244800I0J567D01*
G01Y245557D01*
G03X882284Y246062I-714J0D01*
G01X878347Y249999D02*
X878758Y249588D01*
G02Y248671I-458J-459D01*
G01X878470Y248391D01*
G02X877938Y248170I-533J532D01*
G01X877789D01*
G02X877076Y248466I1J1009D01*
G01X877071Y248470D01*
G02X876872Y248746I751J751D01*
G02X876760Y249220I950J475D01*
G01Y262945D01*
G02X876785Y263053I249J-1D01*
G01X876850Y263188D01*
G01X879700Y262900D02*
X879897Y262703D01*
Y245284D01*
G03X880478Y243932I1862J-1D01*
G01X880483Y243928D01*
G03X880610Y243818I1247J1311D01*
G01X881991Y242730D01*
G02X882284Y242125I-477J-605D01*
G01X875550Y262894D02*
X875960Y262484D01*
Y249221D01*
G03X876156Y248388I1862J-1D01*
G03X876541Y247869I1665J833D01*
G01X876546Y247865D01*
G03X876673Y247755I1247J1311D01*
G01X876985Y247506D01*
X876987Y247504D01*
X877157Y247369D01*
X877238Y247306D01*
X877261Y247288D01*
X877281Y247273D01*
X877367Y247205D01*
X877368D01*
X877394Y247184D01*
X877543Y247068D01*
X877567Y247050D01*
X877577Y247041D01*
X878056Y246663D01*
G02X878347Y246062I-475J-601D01*
G01X888850Y264868D02*
X888571Y264589D01*
Y245285D01*
G03X888882Y244533I1062J-1D01*
G01X888887Y244529D01*
G03X889600Y244233I714J713D01*
G01X889800D01*
G03X890198Y244398I0J563D01*
G01X890482Y244682D01*
G03Y245738I-528J528D01*
G01X890158Y246062D01*
G01X884850Y264594D02*
Y264544D01*
X884800Y264494D01*
X884780D01*
X884634Y264348D01*
Y249221D01*
G03X884945Y248470I1062J0D01*
G01X884950Y248466D01*
G03X885663Y248170I714J713D01*
G01X885863D01*
G03X886217Y248316I1J500D01*
G01X886500Y248601D01*
G03Y249720I-559J560D01*
G01X886221Y249999D01*
G01X887550Y265162D02*
X887771Y265117D01*
Y245287D01*
G03X888352Y243932I1862J-4D01*
G01X888357Y243928D01*
G03X888484Y243818I1247J1311D01*
G01X889865Y242730D01*
G02X890158Y242125I-477J-605D01*
G01X883550Y264300D02*
X883834Y264016D01*
Y249221D01*
G03X884415Y247869I1862J-1D01*
G01X884420Y247865D01*
G03X884547Y247755I1247J1311D01*
G01X885928Y246667D01*
G02X886221Y246062I-477J-605D01*
G01X867971Y150245D02*
X868071D01*
X868321Y149995D01*
X894763D01*
X895673Y150905D01*
Y156555D01*
X895142Y157086D01*
X892426D01*
X891726Y157786D01*
Y159049D01*
G03X891326Y159449I-400J0D01*
G01X890158D01*
G01X886221Y155512D02*
X887389D01*
G03X887789Y155912I0J400D01*
G01Y156312D01*
G03X887034Y157067I-755J0D01*
G01X869217D01*
X868967Y156817D01*
X868867D01*
G01X867971Y148945D02*
X868071D01*
X868321Y149195D01*
X895095D01*
X896473Y150573D01*
Y156887D01*
X895474Y157886D01*
X892758D01*
X892526Y158118D01*
Y159049D01*
G02X892926Y159449I400J0D01*
G01X894095D01*
G01X890158Y155512D02*
X888989D01*
G02X888589Y155912I0J400D01*
G01Y156312D01*
G03X887034Y157867I-1555J0D01*
G01X869217D01*
X868967Y158117D01*
X868673D01*
G01X890158Y151575D02*
X891327D01*
G03X891727Y151975I0J400D01*
G01Y152375D01*
G03X890953Y153149I-774J0D01*
G01X868559D01*
X868309Y152899D01*
X868209D01*
G01X886221Y147638D02*
X886417Y147842D01*
G02X887722Y146586I652J-628D01*
G02X886551Y146088I-1171J1128D01*
G01X870889D01*
X870639Y146338D01*
X870539D01*
G01X871059Y134569D02*
X871351Y134277D01*
X894793D01*
X895673Y135157D01*
Y140807D01*
X895142Y141338D01*
X893067D01*
G02X891726Y142679I0J1341D01*
G01Y143301D01*
G03X891326Y143701I-400J0D01*
G01X890158D01*
G01X894095Y151575D02*
X892927D01*
G02X892527Y151975I0J400D01*
G01Y152375D01*
G03X890953Y153949I-1574J0D01*
G01X868559D01*
X868309Y154199D01*
X868015D01*
G01X890158Y147638D02*
G02X887817Y145643I-7431J6349D01*
G02X886551Y145288I-1264J2072D01*
G01X870889D01*
X870639Y145038D01*
X870539D01*
G01X871047Y133269D02*
X871255Y133477D01*
X895125D01*
X896473Y134825D01*
Y141139D01*
X895474Y142138D01*
X893067D01*
G02X892526Y142679I0J541D01*
G01Y143301D01*
G02X892926Y143701I400J0D01*
G01X894095D01*
G01X896775Y264300D02*
X896445Y263970D01*
Y245284D01*
G03X896756Y244533I1062J0D01*
G01X896761Y244529D01*
G03X897474Y244233I714J713D01*
G01X897674D01*
G03X898241Y244800I0J567D01*
G01Y245557D01*
G03X898032Y246062I-714J0D01*
G01X894095Y249999D02*
G02X894500Y249021I-978J-978D01*
G01Y248800D01*
G02X893870Y248170I-630J0D01*
G01X893537D01*
G02X892824Y248466I1J1009D01*
G01X892819Y248470D01*
G02X892508Y249221I751J751D01*
G01Y264008D01*
X892750Y264250D01*
G01X895475Y264300D02*
X895645Y264130D01*
Y245284D01*
G03X896226Y243932I1862J-1D01*
G01X896231Y243928D01*
G03X896358Y243818I1247J1311D01*
G01X897739Y242730D01*
G02X898032Y242125I-477J-605D01*
G01X891450Y264250D02*
X891708Y263992D01*
Y249221D01*
G03X892289Y247869I1862J-1D01*
G01X892294Y247865D01*
G03X892421Y247755I1247J1311D01*
G01X893802Y246667D01*
G02X894095Y246062I-477J-605D01*
G01X900700Y264400D02*
X900382Y264082D01*
Y249221D01*
G03X900693Y248470I1062J0D01*
G01X900698Y248466D01*
G03X901411Y248170I714J713D01*
G01X901611D01*
G03X902178Y248737I0J567D01*
G01Y249494D01*
G03X901969Y249999I-714J0D01*
G01X899400Y264400D02*
X899582Y264218D01*
Y249221D01*
G03X900163Y247869I1862J-1D01*
G01X900168Y247865D01*
G03X900295Y247755I1247J1311D01*
G01X901676Y246667D01*
G02X901969Y246062I-477J-605D01*
G01X886221Y139764D02*
X887389D01*
G03X887789Y140164I0J400D01*
G01Y140564D01*
G03X887034Y141319I-755J0D01*
G01X871624D01*
X871374Y141069D01*
X871274D01*
G01X871480Y137151D02*
X871580D01*
X871830Y137401D01*
X891243D01*
G02X891719Y136925I0J-476D01*
G01Y136525D01*
G02X891477Y136075I-870J178D01*
G02X890878Y135827I-599J599D01*
G01X890158D01*
G01X871338Y130590D02*
X871438D01*
X871688Y130340D01*
X886142D01*
G03X887434Y130566I0J3806D01*
G01X887666Y130659D01*
G03X887046Y132218I-310J779D01*
G01X886221Y131890D01*
G01X871274Y142369D02*
X871374D01*
X871624Y142119D01*
X887034D01*
G02X888589Y140564I0J-1555D01*
G01Y140164D01*
G03X888989Y139764I400J0D01*
G01X890158D01*
G01X871480Y138451D02*
X871580D01*
X871830Y138201D01*
X891250D01*
G02X892526Y136925I0J-1276D01*
G01Y136525D01*
X892519Y136526D01*
Y136444D01*
G03X892637Y136160I401J0D01*
G01X892639Y136158D01*
G03X893443Y135827I804J811D01*
G01X894095D01*
G01X871338Y129290D02*
X871438D01*
X871688Y129540D01*
X886142D01*
G03X887706Y129813I2J4607D01*
G03X890158Y131890I-1565J4333D01*
G01X904600Y264400D02*
X904319Y264119D01*
Y245284D01*
G03X904630Y244533I1062J0D01*
G01X904635Y244529D01*
G03X905348Y244233I714J713D01*
G01X905633D01*
G03X906157Y244450I0J741D01*
G03X906311Y244863I-477J413D01*
G01Y245084D01*
G03X905906Y246062I-1383J0D01*
G01X903300Y264400D02*
X903519Y264181D01*
Y245284D01*
G03X904100Y243932I1862J-1D01*
G01X904105Y243928D01*
G03X904232Y243818I1247J1311D01*
G01X904717Y243434D01*
X904720Y243431D01*
X904841Y243337D01*
X905005Y243208D01*
X905006Y243206D01*
X905613Y242730D01*
G02X905906Y242125I-477J-605D01*
G01X912400Y264900D02*
X912193Y264693D01*
Y249220D01*
G03X912305Y248746I1062J1D01*
G03X912504Y248470I950J475D01*
G01X912509Y248466D01*
G03X913222Y248170I714J713D01*
G01X913371D01*
G03X913903Y248391I-1J753D01*
G01X913938Y248425D01*
G03X914185Y249021I-596J596D01*
G03X913780Y249999I-1383J0D01*
G01X911100Y265194D02*
Y264900D01*
X911393Y264607D01*
Y249221D01*
G03X911589Y248388I1862J-1D01*
G03X911974Y247869I1665J833D01*
G01X911979Y247865D01*
G03X912106Y247755I1247J1311D01*
G01X912418Y247506D01*
X912420Y247504D01*
X912590Y247369D01*
X912671Y247306D01*
X912694Y247288D01*
X912714Y247273D01*
X912800Y247205D01*
X912801D01*
X912827Y247184D01*
X912976Y247068D01*
X913000Y247050D01*
X913010Y247041D01*
X913489Y246663D01*
G02X913780Y246062I-475J-601D01*
G01X915100Y264994D02*
Y264700D01*
X915330Y264470D01*
Y245284D01*
G03X915526Y244451I1862J-1D01*
G03X915911Y243932I1665J833D01*
G01X915916Y243928D01*
G03X916043Y243818I1247J1311D01*
G01X916355Y243569D01*
X916357Y243567D01*
X916527Y243432D01*
X916608Y243369D01*
X916631Y243351D01*
X916651Y243336D01*
X916737Y243268D01*
X916738D01*
X916764Y243247D01*
X916913Y243131D01*
X916937Y243113D01*
X916947Y243104D01*
X917426Y242726D01*
G02X917717Y242125I-475J-601D01*
G01X915638Y109817D02*
X915703Y109892D01*
X915679Y110244D01*
X917552Y112379D01*
X918432Y114580D01*
Y117447D01*
X920093Y119108D01*
Y124303D01*
G03X917996Y126400I-2097J0D01*
G01X909140D01*
G03X907496Y124756I0J-1644D01*
G01Y123261D01*
G03X907635Y122622I1537J0D01*
G01X907695Y122490D01*
G03X908699Y121698I1271J579D01*
G01X909094Y121622D01*
G02X909843Y120716I-174J-907D01*
G01Y120079D01*
G01X907172Y112044D02*
X907260Y112090D01*
X907356Y112396D01*
X908270Y112873D01*
X909477Y114081D01*
Y115605D01*
G02X910067Y117029I2013J0D01*
G02X911711Y117710I1644J-1643D01*
G01X913380D01*
G02X913780Y117310I0J-400D01*
G01Y116142D01*
G01X913453Y112153D02*
X913537Y112206D01*
X913609Y112534D01*
X915041Y113449D01*
X916152Y115177D01*
Y121118D01*
G02X916681Y121647I529J0D01*
G01X917014D01*
G02X917511Y121441I0J-703D01*
G01X917600Y121352D01*
G02X917717Y121069I-284J-283D01*
G01Y120079D01*
G01X921654Y116142D02*
Y117310D01*
G03X921254Y117710I-400J0D01*
G03X920897Y117562I0J-505D01*
G01X920402Y117067D01*
G03X920114Y116372I695J-695D01*
G01Y115931D01*
G03X920526Y114936I1407J0D01*
G01X921457Y114005D01*
G02X921615Y112169I-1428J-1048D01*
G01X920836Y111390D01*
Y111036D01*
X920766Y110966D01*
G01X914659Y110674D02*
X914724Y110749D01*
X915077Y110772D01*
X916859Y112804D01*
X917632Y114735D01*
Y117779D01*
X919293Y119440D01*
Y124303D01*
G03X917996Y125600I-1297J0D01*
G01X909140D01*
G03X908296Y124756I0J-844D01*
G01Y123261D01*
G03X908363Y122954I737J0D01*
G01X908423Y122822D01*
G03X908852Y122484I543J248D01*
G01X908986Y122458D01*
G03X909101Y122447I115J594D01*
G01X909443D01*
G03X909843Y122847I0J400D01*
G01Y124016D01*
G01X906571Y113197D02*
X906660Y113244D01*
X907026Y113127D01*
X907790Y113526D01*
X908677Y114413D01*
Y115606D01*
G02X909501Y117595I2813J0D01*
G02X911710Y118510I2209J-2209D01*
G01X913380D01*
G03X913780Y118910I0J400D01*
G01Y120079D01*
G01X912752Y113249D02*
X912836Y113302D01*
X913197Y113221D01*
X914462Y114030D01*
X915352Y115413D01*
Y121118D01*
G02X916681Y122447I1329J0D01*
G01X917003D01*
G03X917508Y122656I0J715D01*
G01X917600Y122748D01*
G03X917717Y123031I-284J283D01*
G01Y124016D01*
G01X921654Y120079D02*
Y118910D01*
G02X921254Y118510I-400J0D01*
G03X920331Y118128I-1J-1305D01*
G01X919836Y117633D01*
G03X919314Y116372I1261J-1260D01*
G01Y115931D01*
G03X919960Y114370I2208J-1D01*
G01X920841Y113489D01*
G02X920942Y112628I-812J-532D01*
G01X920268Y111954D01*
X919916Y111955D01*
X919846Y111885D01*
G01X916400Y264700D02*
X916130Y264430D01*
Y245283D01*
G03X916242Y244809I1062J1D01*
G03X916441Y244533I950J475D01*
G01X916446Y244529D01*
G03X917159Y244233I714J713D01*
G01X917308D01*
G03X917840Y244454I-1J753D01*
G01X917875Y244488D01*
G03X918122Y245084I-596J596D01*
G03X917717Y246062I-1383J0D01*
G01X918900Y264700D02*
X919267Y264333D01*
Y249221D01*
G03X919463Y248388I1862J-1D01*
G03X919848Y247869I1665J833D01*
G01X919853Y247865D01*
G03X919980Y247755I1247J1311D01*
G01X920292Y247506D01*
X920294Y247504D01*
X920464Y247369D01*
X920545Y247306D01*
X920568Y247288D01*
X920588Y247273D01*
X920674Y247205D01*
X920675D01*
X920701Y247184D01*
X920850Y247068D01*
X920874Y247050D01*
X920884Y247041D01*
X921363Y246663D01*
G02X921654Y246062I-475J-601D01*
G01X924300Y264700D02*
X924004Y264404D01*
Y245283D01*
G03X924116Y244809I1062J1D01*
G03X924315Y244533I950J475D01*
G01X924320Y244529D01*
G03X925033Y244233I714J713D01*
G01X925182D01*
G03X925714Y244454I-1J753D01*
G01X925749Y244488D01*
G03X925996Y245084I-596J596D01*
G03X925591Y246062I-1383J0D01*
G01X920200Y264700D02*
X920067Y264567D01*
Y249220D01*
G03X920179Y248746I1062J1D01*
G03X920378Y248470I950J475D01*
G01X920383Y248466D01*
G03X921096Y248170I714J713D01*
G01X921245D01*
G03X921777Y248391I-1J753D01*
G01X921812Y248425D01*
G03X922059Y249021I-596J596D01*
G03X921654Y249999I-1383J0D01*
G01X923000Y264994D02*
Y264700D01*
X923204Y264496D01*
Y245284D01*
G03X923400Y244451I1862J-1D01*
G03X923785Y243932I1665J833D01*
G01X923790Y243928D01*
G03X923917Y243818I1247J1311D01*
G01X924229Y243569D01*
X924231Y243567D01*
X924401Y243432D01*
X924482Y243369D01*
X924505Y243351D01*
X924525Y243336D01*
X924611Y243268D01*
X924612D01*
X924638Y243247D01*
X924787Y243131D01*
X924811Y243113D01*
X924821Y243104D01*
X925300Y242726D01*
G02X925591Y242125I-475J-601D01*
G01X934430Y112005D02*
Y112105D01*
X934180Y112355D01*
Y117447D01*
X935841Y119108D01*
Y123973D01*
G03X933414Y126400I-2427J0D01*
G01X924888D01*
G03X923244Y124756I0J-1644D01*
G01Y123261D01*
G03X923383Y122622I1537J0D01*
G01X923443Y122490D01*
G03X924447Y121698I1271J579D01*
G01X924649Y121659D01*
G02X925591Y120079I-854J-1580D01*
G01X924005Y109146D02*
X924075Y109216D01*
Y109570D01*
X924464Y109959D01*
G03X925225Y111796I-1837J1837D01*
G01Y116495D01*
G02X926505Y117775I1280J0D01*
G01X929063D01*
G02X929528Y117310I0J-465D01*
G01Y116142D01*
G01X933130Y112005D02*
Y112105D01*
X933380Y112355D01*
Y117779D01*
X935041Y119440D01*
Y123973D01*
G03X933414Y125600I-1627J0D01*
G01X924888D01*
G03X924044Y124756I0J-844D01*
G01Y123261D01*
G03X924111Y122954I737J0D01*
G01X924171Y122822D01*
G03X924600Y122484I543J248D01*
G01X924734Y122458D01*
G03X924849Y122447I115J594D01*
G01X925191D01*
G03X925591Y122847I0J400D01*
G01Y124016D01*
G01X923085Y110065D02*
X923156Y110136D01*
X923509D01*
X923898Y110525D01*
G03X924425Y111796I-1270J1272D01*
G01Y116495D01*
G02X926505Y118575I2080J0D01*
G01X928994D01*
G03X929528Y119109I0J534D01*
G01Y120079D01*
G01Y246062D02*
G03X929237Y246663I-766J0D01*
G01X928758Y247041D01*
X928748Y247050D01*
X928724Y247068D01*
X928575Y247184D01*
X928549Y247205D01*
X928548D01*
X928462Y247273D01*
X928442Y247288D01*
X928419Y247306D01*
X928338Y247369D01*
X928168Y247504D01*
X928166Y247506D01*
X927854Y247755D01*
G02X927727Y247865I1120J1421D01*
G01X927722Y247869D01*
G02X927337Y248388I1280J1352D01*
G02X927141Y249221I1666J832D01*
G01Y264779D01*
X926900Y265020D01*
Y265120D01*
G01X933465Y246062D02*
G02X933870Y245084I-978J-978D01*
G02X933623Y244488I-843J0D01*
G01X933588Y244454D01*
G02X933056Y244233I-533J532D01*
G01X932907D01*
G02X932194Y244529I1J1009D01*
G01X932189Y244533D01*
G02X931990Y244809I751J751D01*
G02X931878Y245283I950J475D01*
G01Y264678D01*
X932100Y264900D01*
G01X929528Y249999D02*
G02X929933Y249021I-978J-978D01*
G02X929686Y248425I-843J0D01*
G01X929651Y248391D01*
G02X929119Y248170I-533J532D01*
G01X928970D01*
G02X928257Y248466I1J1009D01*
G01X928252Y248470D01*
G02X928053Y248746I751J751D01*
G02X927941Y249220I950J475D01*
G01Y264567D01*
X928200Y264826D01*
G01X933465Y242125D02*
G03X933174Y242726I-766J0D01*
G01X932695Y243104D01*
X932685Y243113D01*
X932661Y243131D01*
X932512Y243247D01*
X932486Y243268D01*
X932485D01*
X932399Y243336D01*
X932379Y243351D01*
X932356Y243369D01*
X932275Y243432D01*
X932105Y243567D01*
X932103Y243569D01*
X931791Y243818D01*
G02X931664Y243928I1120J1421D01*
G01X931659Y243932D01*
G02X931274Y244451I1280J1352D01*
G02X931078Y245284I1666J832D01*
G01Y264622D01*
X930800Y264900D01*
Y265194D01*
G01X930454Y111326D02*
X930524Y111396D01*
Y111750D01*
X931900Y113126D01*
Y121400D01*
G02X932147Y121647I247J0D01*
G01X932762D01*
G02X933259Y121441I0J-703D01*
G01X933348Y121352D01*
G02X933465Y121069I-284J-283D01*
G01Y120079D01*
G01X937255Y111337D02*
Y111437D01*
X937005Y111687D01*
Y114205D01*
X935862Y115348D01*
Y116779D01*
X936793Y117710D01*
X937002D01*
G02X937402Y117310I0J-400D01*
G01Y116142D01*
G01X929534Y112246D02*
X929604Y112316D01*
X929958D01*
X931100Y113458D01*
Y121400D01*
G02X932147Y122447I1047J0D01*
G01X932751D01*
G03X933256Y122656I0J715D01*
G01X933348Y122748D01*
G03X933465Y123031I-284J283D01*
G01Y124016D01*
G01X935955Y111337D02*
Y111437D01*
X936205Y111687D01*
Y113873D01*
X935062Y115016D01*
Y117111D01*
X936461Y118510D01*
X937002D01*
G03X937402Y118910I0J400D01*
G01Y120079D01*
G01X929528Y131890D02*
X929532Y131894D01*
Y132851D01*
G03X928983Y133610I-799J0D01*
G01X928551D01*
G03X928120Y133432I0J-611D01*
G01X928119Y133431D01*
G03X927942Y133002I431J-429D01*
G01Y131049D01*
G02X927563Y130130I-1300J-1D01*
G01X927352Y129919D01*
G02X926433Y129540I-918J921D01*
G01X917067D01*
G02X916148Y129919I-1J1300D01*
G01X915709Y130358D01*
G02X915330Y131277I921J918D01*
G01Y163619D01*
G03X915037Y164326I-999J0D01*
G01X914683Y164680D01*
G03X913976Y164973I-707J-706D01*
G01X872807D01*
X872557Y164723D01*
X872457D01*
G01Y166023D02*
X872557D01*
X872807Y165773D01*
X913976D01*
G02X915249Y165246I1J-1800D01*
G01X915603Y164892D01*
G02X916130Y163619I-1273J-1272D01*
G01Y131276D01*
X916131D01*
G03X916276Y130924I500J0D01*
G01X916714Y130486D01*
G03X917067Y130340I353J354D01*
G01X926433D01*
G03X926786Y130486I0J500D01*
G01X926996Y130696D01*
G03X927142Y131048I-354J353D01*
G01Y133002D01*
G02X927552Y133997I1409J1D01*
G01X927554Y133999D01*
G02X928551Y134410I996J-1000D01*
G01X929099D01*
G03X929532Y134843I0J433D01*
G01Y135823D01*
X929528Y135827D01*
G01X941339Y246062D02*
G02X941744Y245084I-978J-978D01*
G02X941497Y244488I-843J0D01*
G01X941462Y244454D01*
G02X940930Y244233I-533J532D01*
G01X940781D01*
G02X940068Y244529I1J1009D01*
G01X940063Y244533D01*
G02X939864Y244809I751J751D01*
G02X939752Y245283I950J475D01*
G01Y264852D01*
X940000Y265100D01*
G01X937402Y249999D02*
G02X937807Y249021I-978J-978D01*
G02X937560Y248425I-843J0D01*
G01X937525Y248391D01*
G02X936993Y248170I-533J532D01*
G01X936844D01*
G02X936131Y248466I1J1009D01*
G01X936126Y248470D01*
G02X935927Y248746I751J751D01*
G02X935815Y249220I950J475D01*
G01Y264815D01*
X936000Y265000D01*
G01X941339Y242125D02*
G03X941048Y242726I-766J0D01*
G01X940569Y243104D01*
X940559Y243113D01*
X940535Y243131D01*
X940386Y243247D01*
X940360Y243268D01*
X940359D01*
X940273Y243336D01*
X940253Y243351D01*
X940230Y243369D01*
X940149Y243432D01*
X939979Y243567D01*
X939977Y243569D01*
X939665Y243818D01*
G02X939538Y243928I1120J1421D01*
G01X939533Y243932D01*
G02X939148Y244451I1280J1352D01*
G02X938952Y245284I1666J832D01*
G01Y264848D01*
X938700Y265100D01*
G01X937402Y246062D02*
G03X937111Y246663I-766J0D01*
G01X936632Y247041D01*
X936622Y247050D01*
X936598Y247068D01*
X936449Y247184D01*
X936423Y247205D01*
X936422D01*
X936336Y247273D01*
X936316Y247288D01*
X936293Y247306D01*
X936212Y247369D01*
X936042Y247504D01*
X936040Y247506D01*
X935728Y247755D01*
G02X935601Y247865I1120J1421D01*
G01X935596Y247869D01*
G02X935211Y248388I1280J1352D01*
G02X935015Y249221I1666J832D01*
G01Y264685D01*
X934700Y265000D01*
G01X953149Y246062D02*
X953750Y245461D01*
G02Y244750I-356J-356D01*
G01X953396Y244396D01*
G02X953002Y244233I-394J395D01*
G01X952591D01*
G02X951878Y244529I1J1009D01*
G01X951873Y244533D01*
G02X951674Y244809I751J751D01*
G02X951562Y245283I950J475D01*
G01Y264464D01*
G02X951631Y264631I237J0D01*
G01X951700Y264700D01*
G01X953149Y242125D02*
G03X952858Y242726I-766J0D01*
G01X952379Y243104D01*
X952369Y243113D01*
X952345Y243131D01*
X952298Y243166D01*
X952282Y243179D01*
X952196Y243247D01*
X952170Y243268D01*
X952169D01*
X952083Y243336D01*
X952063Y243351D01*
X952040Y243369D01*
X951959Y243432D01*
X951789Y243567D01*
X951787Y243569D01*
X951475Y243818D01*
G02X951348Y243928I1120J1421D01*
G01X951343Y243932D01*
G02X950958Y244451I1280J1352D01*
G02X950762Y245284I1666J832D01*
G01Y264338D01*
X950400Y264700D01*
G01X943500Y142966D02*
Y144200D01*
X942430Y145270D01*
X938542D01*
G03X937736Y144936I0J-1140D01*
G01X937721Y144921D01*
G03X937402Y144152I769J-770D01*
G01Y143701D01*
G01X944800Y142932D02*
Y143200D01*
X944300Y143700D01*
Y144532D01*
X942762Y146070D01*
X938781D01*
G02X937402Y146827I0J1635D01*
G01Y147638D01*
G01X938800Y113800D02*
Y114339D01*
X938989Y114528D01*
Y140370D01*
X938045Y141314D01*
X932527D01*
X931074Y142767D01*
Y144736D01*
G03X930541Y145269I-533J0D01*
G01X929928D01*
G03X929528Y144869I0J-400D01*
G01Y143701D01*
G01X940100Y113800D02*
X939789Y114111D01*
Y140702D01*
X938377Y142114D01*
X932859D01*
X931874Y143099D01*
Y144736D01*
G03X930541Y146069I-1333J0D01*
G02X929969Y146227I0J1113D01*
G02X929528Y147292I1065J1065D01*
G01Y147638D01*
G01X955800Y264500D02*
X955499Y264199D01*
Y249220D01*
G03X955611Y248746I1062J1D01*
G03X955810Y248470I950J475D01*
G01X955815Y248466D01*
G03X956528Y248170I714J713D01*
G01X956677D01*
G03X957209Y248391I-1J753D01*
G01X957244Y248425D01*
G03X957491Y249021I-596J596D01*
G03X957086Y249999I-1383J0D01*
G01X954500Y264500D02*
X954699Y264301D01*
Y249221D01*
G03X954895Y248388I1862J-1D01*
G03X955280Y247869I1665J833D01*
G01X955285Y247865D01*
G03X955412Y247755I1247J1311D01*
G01X955724Y247506D01*
X955726Y247504D01*
X955896Y247369D01*
X955977Y247306D01*
X956000Y247288D01*
X956020Y247273D01*
X956106Y247205D01*
X956107D01*
X956133Y247184D01*
X956282Y247068D01*
X956306Y247050D01*
X956316Y247041D01*
X956795Y246663D01*
G02X957086Y246062I-475J-601D01*
G01X961023D02*
G02X961428Y245084I-978J-978D01*
G02X961181Y244488I-843J0D01*
G01X961146Y244454D01*
G02X960614Y244233I-533J532D01*
G01X960465D01*
G02X959752Y244529I1J1009D01*
G01X959747Y244533D01*
G02X959548Y244809I751J751D01*
G02X959436Y245283I950J475D01*
G01Y264213D01*
X959723Y264500D01*
G01X961023Y242125D02*
G03X960732Y242726I-766J0D01*
G01X960253Y243104D01*
X960243Y243113D01*
X960219Y243131D01*
X960070Y243247D01*
X960044Y243268D01*
X960043D01*
X959957Y243336D01*
X959937Y243351D01*
X959914Y243369D01*
X959833Y243432D01*
X959663Y243567D01*
X959661Y243569D01*
X959349Y243818D01*
G02X959222Y243928I1120J1421D01*
G01X959217Y243932D01*
G02X958832Y244451I1280J1352D01*
G02X958636Y245284I1666J832D01*
G01Y264287D01*
X958423Y264500D01*
G01X967597Y264497D02*
X967310Y264210D01*
Y245283D01*
G03X967422Y244809I1062J1D01*
G03X967621Y244533I950J475D01*
G01X967626Y244529D01*
G03X968339Y244233I714J713D01*
G01X968488D01*
G03X969020Y244454I-1J753D01*
G01X969055Y244488D01*
G03X969302Y245084I-596J596D01*
G03X968897Y246062I-1383J0D01*
G01X963623Y264500D02*
X963373Y264250D01*
Y249220D01*
G03X963485Y248746I1062J1D01*
G03X963684Y248470I950J475D01*
G01X963689Y248466D01*
G03X964402Y248170I714J713D01*
G01X964551D01*
G03X965083Y248391I-1J753D01*
G01X965118Y248425D01*
G03X965365Y249021I-596J596D01*
G03X964960Y249999I-1383J0D01*
G01X966297Y264497D02*
X966510Y264284D01*
Y245284D01*
G03X966706Y244451I1862J-1D01*
G03X967091Y243932I1665J833D01*
G01X967096Y243928D01*
G03X967223Y243818I1247J1311D01*
G01X967535Y243569D01*
X967537Y243567D01*
X967707Y243432D01*
X967788Y243369D01*
X967811Y243351D01*
X967831Y243336D01*
X967917Y243268D01*
X967918D01*
X967944Y243247D01*
X968093Y243131D01*
X968117Y243113D01*
X968127Y243104D01*
X968606Y242726D01*
G02X968897Y242125I-475J-601D01*
G01X962323Y264500D02*
X962573Y264250D01*
Y249221D01*
G03X962769Y248388I1862J-1D01*
G03X963154Y247869I1665J833D01*
G01X963159Y247865D01*
G03X963286Y247755I1247J1311D01*
G01X963598Y247506D01*
X963600Y247504D01*
X963770Y247369D01*
X963851Y247306D01*
X963874Y247288D01*
X963894Y247273D01*
X963980Y247205D01*
X963981D01*
X964007Y247184D01*
X964156Y247068D01*
X964180Y247050D01*
X964190Y247041D01*
X964669Y246663D01*
G02X964960Y246062I-475J-601D01*
G01X971497Y264697D02*
X971247Y264447D01*
Y249220D01*
G03X971359Y248746I1062J1D01*
G03X971558Y248470I950J475D01*
G01X971563Y248466D01*
G03X972276Y248170I714J713D01*
G01X972425D01*
G03X972957Y248391I-1J753D01*
G01X972992Y248425D01*
G03X973239Y249021I-596J596D01*
G03X972834Y249999I-1383J0D01*
G01X970197Y264697D02*
X970447Y264447D01*
Y249221D01*
G03X970643Y248388I1862J-1D01*
G03X971028Y247869I1665J833D01*
G01X971033Y247865D01*
G03X971160Y247755I1247J1311D01*
G01X971472Y247506D01*
X971474Y247504D01*
X971644Y247369D01*
X971725Y247306D01*
X971748Y247288D01*
X971768Y247273D01*
X971854Y247205D01*
X971855D01*
X971881Y247184D01*
X972030Y247068D01*
X972054Y247050D01*
X972064Y247041D01*
X972543Y246663D01*
G02X972834Y246062I-475J-601D01*
G01X975400Y264500D02*
X975184Y264284D01*
Y245283D01*
G03X975296Y244809I1062J1D01*
G03X975495Y244533I950J475D01*
G01X975500Y244529D01*
G03X976213Y244233I714J713D01*
G01X976362D01*
G03X976894Y244454I-1J753D01*
G01X976929Y244488D01*
G03X977176Y245084I-596J596D01*
G03X976771Y246062I-1383J0D01*
G01X974100Y264500D02*
X974384Y264216D01*
Y245284D01*
G03X974580Y244451I1862J-1D01*
G03X974965Y243932I1665J833D01*
G01X974970Y243928D01*
G03X975097Y243818I1247J1311D01*
G01X975409Y243569D01*
X975411Y243567D01*
X975581Y243432D01*
X975662Y243369D01*
X975685Y243351D01*
X975705Y243336D01*
X975791Y243268D01*
X975792D01*
X975818Y243247D01*
X975967Y243131D01*
X975991Y243113D01*
X976001Y243104D01*
X976480Y242726D01*
G02X976771Y242125I-475J-601D01*
G01X991184Y264584D02*
X990932Y264332D01*
Y249220D01*
G03X991044Y248746I1062J1D01*
G03X991243Y248470I950J475D01*
G01X991248Y248466D01*
G03X991961Y248170I714J713D01*
G01X992110D01*
G03X992642Y248391I-1J753D01*
G01X992677Y248425D01*
G03X992924Y249021I-596J596D01*
G03X992519Y249999I-1383J0D01*
G01X987200Y264500D02*
X986995Y264295D01*
Y245283D01*
G03X987107Y244809I1062J1D01*
G03X987306Y244533I950J475D01*
G01X987311Y244529D01*
G03X988024Y244233I714J713D01*
G01X988173D01*
G03X988705Y244454I-1J753D01*
G01X988740Y244488D01*
G03X988987Y245084I-596J596D01*
G03X988582Y246062I-1383J0D01*
G01X980708Y249999D02*
G02X981113Y249021I-978J-978D01*
G02X980866Y248425I-843J0D01*
G01X980831Y248391D01*
G02X980299Y248170I-533J532D01*
G01X980150D01*
G02X979437Y248466I1J1009D01*
G01X979432Y248470D01*
G02X979233Y248746I751J751D01*
G02X979121Y249220I950J475D01*
G01Y264321D01*
X979400Y264600D01*
G01X992519Y246062D02*
G03X992228Y246663I-766J0D01*
G01X991749Y247041D01*
X991739Y247050D01*
X991715Y247068D01*
X991566Y247184D01*
X991540Y247205D01*
X991539D01*
X991453Y247273D01*
X991433Y247288D01*
X991410Y247306D01*
X991329Y247369D01*
X991159Y247504D01*
X991157Y247506D01*
X990845Y247755D01*
G02X990718Y247865I1120J1421D01*
G01X990713Y247869D01*
G02X990328Y248388I1280J1352D01*
G02X990132Y249221I1666J832D01*
G01Y264336D01*
X989884Y264584D01*
G01X985900Y264500D02*
X986195Y264205D01*
Y245284D01*
G03X986391Y244451I1862J-1D01*
G03X986776Y243932I1665J833D01*
G01X986781Y243928D01*
G03X986908Y243818I1247J1311D01*
G01X987220Y243569D01*
X987222Y243567D01*
X987392Y243432D01*
X987473Y243369D01*
X987496Y243351D01*
X987516Y243336D01*
X987602Y243268D01*
X987603D01*
X987629Y243247D01*
X987778Y243131D01*
X987802Y243113D01*
X987812Y243104D01*
X988291Y242726D01*
G02X988582Y242125I-475J-601D01*
G01X980708Y246062D02*
G03X980417Y246663I-766J0D01*
G01X979938Y247041D01*
X979928Y247050D01*
X979904Y247068D01*
X979755Y247184D01*
X979729Y247205D01*
X979728D01*
X979642Y247273D01*
X979622Y247288D01*
X979599Y247306D01*
X979518Y247369D01*
X979348Y247504D01*
X979346Y247506D01*
X979034Y247755D01*
G02X978907Y247865I1120J1421D01*
G01X978902Y247869D01*
G02X978517Y248388I1280J1352D01*
G02X978321Y249221I1666J832D01*
G01Y264379D01*
X978100Y264600D01*
G01X873250Y126403D02*
X890801D01*
X891708Y127310D01*
Y127759D01*
X894289Y130340D01*
X894738D01*
X895645Y131247D01*
Y131696D01*
X898219Y134270D01*
X898668D01*
X899603Y135205D01*
Y137398D01*
X901969Y139764D01*
G01X872092Y122470D02*
X872096Y122466D01*
X890801D01*
X891708Y123373D01*
Y124208D01*
X893903Y126403D01*
X894738D01*
X895645Y127310D01*
Y128315D01*
X897670Y130340D01*
X898675D01*
X900225Y131890D01*
X901969D01*
G01X946287Y142267D02*
Y142367D01*
X946537Y142617D01*
Y144633D01*
X942099Y149071D01*
G03X941816Y149188I-283J-284D01*
G01X937173D01*
G03X936466Y148895I0J-999D01*
G01X936145Y148574D01*
G03X935852Y147867I706J-707D01*
G01Y146894D01*
G02X934258Y145300I-1594J0D01*
G01X933955D01*
G03X933465Y144810I0J-490D01*
G01Y143701D01*
G01X947587Y142267D02*
Y142367D01*
X947337Y142617D01*
Y144966D01*
X942665Y149638D01*
G03X941816Y149988I-848J-851D01*
G01X937173D01*
G03X935900Y149461I-1J-1800D01*
G01X935579Y149140D01*
G03X935052Y147867I1273J-1272D01*
G01Y146894D01*
G02X934258Y146100I-794J0D01*
G01X934165D01*
X934098Y146112D01*
G02X933465Y146869I136J757D01*
G01Y147638D01*
G01X950549Y114119D02*
Y114219D01*
X950799Y114469D01*
Y144606D01*
G03X950567Y145167I-794J0D01*
G03X950004Y145400I-563J-564D01*
G03X949212Y144550I60J-850D01*
G01Y143701D01*
G01X951849Y114119D02*
Y114219D01*
X951599Y114469D01*
Y144607D01*
G03X951132Y145734I-1594J0D01*
G03X950006Y146200I-1126J-1127D01*
G01X949650D01*
G02X949212Y146638I0J438D01*
G01Y147638D01*
G01X957897Y111376D02*
X957190D01*
X955558Y113008D01*
Y117782D01*
G02X955827Y118364I764J0D01*
G02X957086Y117782I495J-582D01*
G01Y116142D01*
G01X961250Y111484D02*
X961562Y111796D01*
Y113410D01*
X961270Y113702D01*
Y117489D01*
X961891Y118111D01*
G03X962484Y119366I-1677J1560D01*
G01X962661Y120691D01*
G03X961823Y121647I-838J111D01*
G01X961423D01*
G03X961023Y121247I0J-400D01*
G01Y120079D01*
G01X956967Y110467D02*
X954758Y112676D01*
Y117782D01*
G02X955308Y118973I1565J0D01*
G02X957086Y120079I4565J-5357D01*
G01X962550Y111484D02*
X962362Y111672D01*
Y113742D01*
X962070Y114034D01*
Y117157D01*
X962467Y117554D01*
G03X963277Y119260I-2254J2116D01*
G01X963454Y120585D01*
G03X961823Y122447I-1631J217D01*
G01X961423D01*
G02X961023Y122847I0J400D01*
G01Y124016D01*
G01X972834Y139764D02*
X973446D01*
X975796Y137414D01*
X979886D01*
X979923Y137377D01*
X981351D01*
X982258Y136470D01*
Y133842D01*
X982660Y133440D01*
X985288D01*
X986195Y132533D01*
Y130860D01*
X987553Y129503D01*
X989225D01*
X990132Y128596D01*
Y126923D01*
X991490Y125566D01*
X993162D01*
X994069Y124659D01*
Y122986D01*
X995427Y121629D01*
X997099D01*
X998006Y120722D01*
Y115204D01*
X999568Y113642D01*
X1002192D01*
G01X998879Y110284D02*
X998779D01*
X998179Y109684D01*
X996257D01*
X990944Y114997D01*
Y121117D01*
X989618Y122443D01*
X987932D01*
X987027Y123348D01*
Y125051D01*
X985697Y126381D01*
X983617D01*
X983092Y126906D01*
Y128986D01*
X981756Y130322D01*
X972120D01*
X971247Y131195D01*
Y145288D01*
X968897Y147638D01*
G01X998879Y108284D02*
X998779D01*
X998179Y108884D01*
X995925D01*
X990144Y114665D01*
Y120785D01*
X989286Y121643D01*
X987600D01*
X986227Y123016D01*
Y124719D01*
X985365Y125581D01*
X983285D01*
X982292Y126574D01*
Y128654D01*
X981424Y129522D01*
X971788D01*
X970447Y130863D01*
Y134277D01*
X968897Y135827D01*
G01X972834Y151575D02*
X973225D01*
X975221Y149579D01*
Y139121D01*
X976128Y138214D01*
X980218D01*
X980255Y138177D01*
X981683D01*
X983058Y136802D01*
Y134442D01*
X983260Y134240D01*
X985620D01*
X986995Y132865D01*
Y131420D01*
X987032Y131383D01*
Y131247D01*
X987939Y130340D01*
X988500D01*
X988537Y130303D01*
X989557D01*
X990932Y128928D01*
Y127255D01*
X991294Y126894D01*
X991822Y126366D01*
X993494D01*
X994869Y124991D01*
Y123318D01*
X994894Y123294D01*
X995759Y122429D01*
X997431D01*
X998843Y121017D01*
Y115499D01*
X999800Y114542D01*
X1001669D01*
G01X995350Y113850D02*
X994069Y115131D01*
Y120722D01*
X993125Y121666D01*
X991544D01*
X990132Y123078D01*
Y124659D01*
X989225Y125566D01*
X987644D01*
X986195Y127015D01*
Y128596D01*
X985288Y129503D01*
X983707D01*
X981320Y131890D01*
X980708D01*
G01X976771Y151575D02*
Y149831D01*
X979121Y147481D01*
Y143095D01*
X980102Y142114D01*
X981683D01*
X983058Y140739D01*
Y139158D01*
X984038Y138178D01*
X985619D01*
X987032Y136765D01*
Y135184D01*
X987976Y134240D01*
X990292D01*
X994906Y129626D01*
Y127310D01*
X995813Y126403D01*
X997484D01*
X998843Y125044D01*
Y123373D01*
X999750Y122466D01*
X1001331D01*
X1002780Y121017D01*
Y119436D01*
X1003687Y118529D01*
X1018392D01*
X1021561Y115360D01*
X1022398D01*
G01X1019327Y137913D02*
G03X1018600Y138214I-727J-727D01*
G01X1009154D01*
G02X1008267Y139101I0J887D01*
G01Y139764D01*
G01Y131890D02*
G03X1006698Y130321I0J-1569D01*
G01Y127583D01*
G03X1007881Y126400I1183J0D01*
G01X1021932D01*
X1022239Y126093D01*
X1022407D01*
G01X1022776Y130594D02*
X1022485Y130303D01*
X1015260D01*
G02X1014567Y130996I0J693D01*
G01Y132653D01*
G03X1012957Y134263I-1610J0D01*
G01X1004131D01*
G02Y135827I0J782D01*
G01X1004330D01*
G01X1018407Y136993D02*
G03X1017391Y137414I-1016J-1015D01*
G01X1006637D01*
G02X1005019Y138080I0J2298D01*
G01X1005015Y138084D01*
G02X1004330Y139727I1628J1643D01*
G01Y139764D01*
G01X1018550Y141444D02*
X1018420Y141314D01*
X1003675D01*
G02X1002147Y141947I0J2161D01*
G01X1000393Y143701D01*
G01X1022407Y124793D02*
X1021600Y125600D01*
X1007881D01*
G02X1005898Y127583I0J1983D01*
G01Y130322D01*
G03X1004330Y131890I-1568J0D01*
G01X1000393Y135827D02*
G03X1003863Y133463I3470J1365D01*
G01X1012957D01*
G02X1013767Y132653I0J-810D01*
G01Y130996D01*
G03X1015260Y129503I1493J0D01*
G01X1022517D01*
X1022726Y129294D01*
X1022776D01*
G01X1029683Y119466D02*
Y119566D01*
X1029083Y120166D01*
Y121074D01*
X1027727Y122430D01*
X1003703D01*
X1002768Y123365D01*
Y129036D01*
X1001483Y130321D01*
X999367D01*
X998814Y130874D01*
Y133413D01*
X997969Y134258D01*
X995524D01*
X990965Y138817D01*
Y141072D01*
X989919Y142118D01*
X987760D01*
X986316Y143562D01*
Y153841D01*
X984645Y155512D01*
G01X1027683Y119466D02*
Y119566D01*
X1028283Y120166D01*
Y120742D01*
X1027395Y121630D01*
X1003371D01*
X1001968Y123033D01*
Y128704D01*
X1001151Y129521D01*
X999035D01*
X998014Y130542D01*
Y133081D01*
X997637Y133458D01*
X995192D01*
X990165Y138485D01*
Y140740D01*
X989587Y141318D01*
X987028D01*
X984645Y143701D01*
G01X976771Y147638D02*
Y145894D01*
X978321Y144344D01*
Y142179D01*
X979186Y141314D01*
X981351D01*
X982258Y140407D01*
Y138735D01*
X983616Y137377D01*
X985288D01*
X986195Y136470D01*
Y134797D01*
X987553Y133440D01*
X989960D01*
X994069Y129331D01*
Y127015D01*
X995481Y125603D01*
X997152D01*
X998042Y124713D01*
Y123043D01*
X998049Y123035D01*
X999418Y121666D01*
X1000999D01*
X1001980Y120685D01*
Y119104D01*
X1003392Y117692D01*
X1017308D01*
X1018200Y116800D01*
G01X996916Y114000D02*
X994869Y116047D01*
Y121054D01*
X993457Y122466D01*
X991876D01*
X990932Y123410D01*
Y124991D01*
X989557Y126366D01*
X987976D01*
X986995Y127347D01*
Y128928D01*
X985583Y130340D01*
X984002D01*
X983095Y131247D01*
Y131873D01*
X981528Y133440D01*
X980902D01*
X978515Y135827D01*
X976771D01*
G01X1018600Y142744D02*
X1017944D01*
X1017314Y142114D01*
X1007051D01*
G02X1005115Y142916I0J2738D01*
G01X1004330Y143701D01*
G01X1022300Y146301D02*
X1021699D01*
X1021474Y146076D01*
X1007283D01*
G02X1006600Y146759I0J683D01*
G02X1007291Y147638I905J0D01*
G01X1008267D01*
G01X1004330Y151575D02*
G03X1002992Y150607I-319J-968D01*
G03X1003599Y150000I607J0D01*
G01X1021000D01*
X1021268Y150268D01*
G01X1023750Y155651D02*
X1022851D01*
X1021125Y153925D01*
X1010500D01*
G02X1009397Y154382I0J1560D01*
G01X1008267Y155512D01*
G01X1020800Y160300D02*
X1020200D01*
X1017799Y157899D01*
X1006500D01*
G02X1005441Y158337I-1J1497D01*
G01X1004330Y159449D01*
G01X1008267Y167323D02*
G02X1007300Y168290I0J967D01*
G01Y168300D01*
G02X1007910Y168910I610J0D01*
G01X1022090D01*
X1022340Y168660D01*
G01X1023022Y172560D02*
X1022735Y172847D01*
X1003973D01*
G03X1003439Y172532I0J-610D01*
G03X1003363Y172237I535J-295D01*
G01Y172227D01*
G03X1004330Y171260I967J0D01*
G01X1022500Y176497D02*
X1022213Y176784D01*
X1007910D01*
G03X1007376Y176469I0J-610D01*
G03X1007300Y176174I535J-295D01*
G01Y176164D01*
G03X1008267Y175197I967J0D01*
G01X1022300Y145001D02*
X1021628D01*
X1021353Y145276D01*
X1007282D01*
G02X1005800Y146758I0J1482D01*
G03X1004330Y147638I-998J0D01*
G01X1022000Y148968D02*
X1021332D01*
X1021100Y149200D01*
X1003599D01*
G02X1002192Y150607I0J1407D01*
G03X1001312Y151575I-972J0D01*
G01X1000393D01*
G01X1023700Y154351D02*
X1022683D01*
X1021457Y153125D01*
X1007489D01*
G02X1006171Y153671I0J1864D01*
G01X1004330Y155512D01*
G01X1020700Y159000D02*
X1020032D01*
X1018131Y157099D01*
X1003411D01*
G02X1002271Y157571I0J1612D01*
G01X1000393Y159449D01*
G01X1004330Y167323D02*
G03X1006449Y168573I0J2421D01*
G01X1006675Y168982D01*
G02X1007910Y169710I1234J-682D01*
G01X1022090D01*
X1022340Y169960D01*
G01X1022728Y173860D02*
X1022515Y173647D01*
X1003973D01*
G03X1002738Y172919I-1J-1410D01*
G01X1002512Y172510D01*
G02X1000393Y171260I-2119J1171D01*
G01X1022397Y177797D02*
X1022184Y177584D01*
X1007910D01*
G03X1006675Y176856I-1J-1410D01*
G01X1006449Y176447D01*
G02X1004330Y175197I-2119J1171D01*
G01X1022200Y180400D02*
G03X1021425Y180721I-775J-775D01*
G01X1003973D01*
G03X1003439Y180406I0J-610D01*
G03X1003363Y180111I535J-295D01*
G01Y180101D01*
G03X1004330Y179134I967J0D01*
G01Y190944D02*
G02X1003363Y191911I0J967D01*
G01Y191921D01*
G02X1003439Y192216I611J0D01*
G02X1003973Y192531I534J-295D01*
G01X1021669D01*
X1022000Y192200D01*
G01X1008267Y194881D02*
G02X1007300Y195848I0J967D01*
G01Y195858D01*
G02X1007376Y196153I611J0D01*
G02X1007910Y196468I534J-295D01*
G01X1022232D01*
X1022500Y196200D01*
G01X1022700Y200100D02*
X1022395Y200405D01*
X1003973D01*
G03X1003439Y200090I0J-610D01*
G03X1003363Y199795I535J-295D01*
G01Y199785D01*
G03X1004330Y198818I967J0D01*
G01X1008267Y206692D02*
G02X1007300Y207659I0J967D01*
G01Y207669D01*
G02X1007376Y207964I611J0D01*
G02X1007910Y208279I534J-295D01*
G01X1022421D01*
X1022600Y208100D01*
G01X1022494Y181700D02*
G02X1022062Y181521I-432J432D01*
G01X1003973D01*
G03X1002738Y180793I-1J-1410D01*
G01X1002512Y180384D01*
G02X1000393Y179134I-2119J1171D01*
G01Y190944D02*
G03X1002512Y192194I0J2421D01*
G01X1002738Y192603D01*
G02X1003973Y193331I1234J-682D01*
G01X1021831D01*
X1022000Y193500D01*
G01X1004330Y194881D02*
G03X1006449Y196131I0J2421D01*
G01X1006675Y196540D01*
G02X1007910Y197268I1234J-682D01*
G01X1022262D01*
X1022494Y197500D01*
G01Y201400D02*
X1022299Y201205D01*
X1003973D01*
G03X1002738Y200477I-1J-1410D01*
G01X1002512Y200068D01*
G02X1000393Y198818I-2119J1171D01*
G01X1004330Y206692D02*
G03X1006449Y207942I0J2421D01*
G01X1006675Y208351D01*
G02X1007910Y209079I1234J-682D01*
G01X1022279D01*
X1022600Y209400D01*
G01Y211900D02*
X1022284Y212216D01*
X1003973D01*
G03X1003439Y211901I0J-610D01*
G03X1003363Y211606I535J-295D01*
G01Y211596D01*
G03X1004330Y210629I967J0D01*
G01X1008267Y214566D02*
G02X1007357Y215202I0J969D01*
G02X1007354Y215212I925J283D01*
G02X1007342Y215247I909J331D01*
G02X1007333Y215279I927J278D01*
G02X1007302Y215461I934J253D01*
G02X1007300Y215533I966J63D01*
G01Y215543D01*
G02X1007376Y215838I611J0D01*
G02X1007910Y216153I534J-295D01*
G01X1022750D01*
X1023000Y215903D01*
G01X1022600Y219700D02*
X1022210Y220090D01*
X1003973D01*
G03X1003439Y219775I0J-610D01*
G03X1003363Y219480I535J-295D01*
G01Y219470D01*
G03X1004330Y218503I967J0D01*
G01X1008267Y222440D02*
G02X1007300Y223407I0J967D01*
G01Y223417D01*
G02X1007376Y223712I611J0D01*
G02X1007910Y224027I534J-295D01*
G01X1022673D01*
X1023000Y223700D01*
G01X1022000Y227700D02*
X1021736Y227964D01*
X1003973D01*
G03X1003439Y227649I0J-610D01*
G03X1003363Y227354I535J-295D01*
G01Y227344D01*
G03X1004330Y226377I967J0D01*
G01X1023936Y232578D02*
X1023259Y231901D01*
X1007910D01*
G03X1007376Y231586I0J-610D01*
G03X1007300Y231291I535J-295D01*
G01Y231281D01*
G03X1008267Y230314I967J0D01*
G01X1004330Y234251D02*
X1003416Y235166D01*
G02X1002780Y236700I1534J1535D01*
G01Y238486D01*
G02X1002787Y238594I833J0D01*
G02X1003024Y239075I826J-108D01*
G01X1003474Y239525D01*
G02X1003898Y239731I512J-515D01*
G02X1003946Y239736I99J-720D01*
G02X1003988Y239738I56J-724D01*
G01X1022770D01*
X1022916Y239884D01*
X1023592Y240478D01*
G01X1022894Y213200D02*
X1022710Y213016D01*
X1003973D01*
G03X1002738Y212288I-1J-1410D01*
G01X1002512Y211879D01*
G02X1000393Y210629I-2119J1171D01*
G01X1022894Y217203D02*
X1022644Y216953D01*
X1007910D01*
G03X1006675Y216225I-1J-1410D01*
G03X1006413Y215399I1934J-1068D01*
G02X1005201Y214582I-1212J490D01*
G02X1004330Y214566I-871J23720D01*
G01X1022894Y221000D02*
X1022784Y220890D01*
X1003973D01*
G03X1002738Y220162I-1J-1410D01*
G01X1002512Y219753D01*
G02X1000393Y218503I-2119J1171D01*
G01X1004330Y222440D02*
G03X1006449Y223690I0J2421D01*
G01X1006675Y224099D01*
G02X1007910Y224827I1234J-682D01*
G01X1022721D01*
X1022894Y225000D01*
G01X1000393Y226377D02*
G03X1002512Y227627I0J2421D01*
G01X1002738Y228036D01*
G02X1003973Y228764I1234J-682D01*
G01X1021764D01*
X1022000Y229000D01*
G01X1004330Y230314D02*
X1005874Y231857D01*
G02X1007910Y232701I2037J-2036D01*
G01X1022355D01*
X1023141Y233487D01*
X1023178Y233640D01*
X1023263Y233691D01*
G01X1000393Y234251D02*
X1000970D01*
G03X1001450Y234450I0J679D01*
G01X1001650Y234650D01*
X1001754Y234753D01*
G03X1001980Y235300I-547J546D01*
G01Y238700D01*
G02X1002307Y239491I1118J1D01*
G01X1002308D01*
X1002858Y240041D01*
X1003041Y240223D01*
G02X1003800Y240538I760J-759D01*
G01X1021731D01*
X1022058Y240865D01*
X1022736Y241457D01*
G01X1001700Y264500D02*
Y264450D01*
X1001943Y264207D01*
Y245284D01*
G03X1002139Y244451I1862J-1D01*
G03X1002524Y243932I1665J833D01*
G01X1002529Y243928D01*
G03X1002656Y243818I1247J1311D01*
G01X1002968Y243569D01*
X1002970Y243567D01*
X1003140Y243432D01*
X1003221Y243369D01*
X1003244Y243351D01*
X1003264Y243336D01*
X1003350Y243268D01*
X1003351D01*
X1003377Y243247D01*
X1003526Y243131D01*
X1003550Y243113D01*
X1003560Y243104D01*
X1004039Y242726D01*
G02X1004330Y242125I-475J-601D01*
G01X993901Y264601D02*
X994069Y264433D01*
Y245284D01*
G03X994265Y244451I1862J-1D01*
G03X994650Y243932I1665J833D01*
G01X994655Y243928D01*
G03X994782Y243818I1247J1311D01*
G01X995094Y243569D01*
X995096Y243567D01*
X995266Y243432D01*
X995347Y243369D01*
X995370Y243351D01*
X995390Y243336D01*
X995476Y243268D01*
X995477D01*
X995503Y243247D01*
X995652Y243131D01*
X995676Y243113D01*
X995686Y243104D01*
X996165Y242726D01*
G02X996456Y242125I-475J-601D01*
G01X1007000Y264500D02*
X1006680Y264180D01*
Y249220D01*
G03X1006792Y248746I1062J1D01*
G03X1006991Y248470I950J475D01*
G01X1006996Y248466D01*
G03X1007709Y248170I714J713D01*
G01X1007858D01*
G03X1008390Y248391I-1J753D01*
G01X1008425Y248425D01*
G03X1008672Y249021I-596J596D01*
G03X1008267Y249999I-1383J0D01*
G01X1003000Y264500D02*
X1002743Y264243D01*
Y245283D01*
G03X1002855Y244809I1062J1D01*
G03X1003054Y244533I950J475D01*
G01X1003059Y244529D01*
G03X1003772Y244233I714J713D01*
G01X1003855D01*
G03X1004159Y244359I0J430D01*
G01X1004500Y244700D01*
G03Y245892I-596J596D01*
G01X1004330Y246062D01*
G01X999150Y264780D02*
X998806Y264436D01*
Y249220D01*
G03X998918Y248746I1062J1D01*
G03X999117Y248470I950J475D01*
G01X999122Y248466D01*
G03X999835Y248170I714J713D01*
G01X999984D01*
G03X1000516Y248391I-1J753D01*
G01X1000551Y248425D01*
G03X1000798Y249021I-596J596D01*
G03X1000393Y249999I-1383J0D01*
G01X995201Y264601D02*
X994869Y264269D01*
Y245283D01*
G03X994981Y244809I1062J1D01*
G03X995180Y244533I950J475D01*
G01X995185Y244529D01*
G03X995898Y244233I714J713D01*
G01X996047D01*
G03X996579Y244454I-1J753D01*
G01X996614Y244488D01*
G03X996861Y245084I-596J596D01*
G03X996456Y246062I-1383J0D01*
G01X1008267D02*
G03X1007976Y246663I-766J0D01*
G01X1007497Y247041D01*
X1007487Y247050D01*
X1007463Y247068D01*
X1007314Y247184D01*
X1007288Y247205D01*
X1007287D01*
X1007201Y247273D01*
X1007181Y247288D01*
X1007158Y247306D01*
X1007077Y247369D01*
X1006907Y247504D01*
X1006905Y247506D01*
X1006593Y247755D01*
G02X1006466Y247865I1120J1421D01*
G01X1006461Y247869D01*
G02X1006076Y248388I1280J1352D01*
G02X1005880Y249221I1666J832D01*
G01Y264320D01*
X1005700Y264500D01*
G01X1000393Y246062D02*
G03X1000102Y246663I-766J0D01*
G01X999623Y247041D01*
X999613Y247050D01*
X999589Y247068D01*
X999440Y247184D01*
X999414Y247205D01*
X999413D01*
X999327Y247273D01*
X999307Y247288D01*
X999284Y247306D01*
X999203Y247369D01*
X999033Y247504D01*
X999031Y247506D01*
X998719Y247755D01*
G02X998592Y247865I1120J1421D01*
G01X998587Y247869D01*
G02X998202Y248388I1280J1352D01*
G02X998006Y249221I1666J832D01*
G01Y264770D01*
X997850Y264926D01*
G01X1009600Y264500D02*
X1009817Y264283D01*
Y245284D01*
G03X1010013Y244451I1862J-1D01*
G03X1010398Y243932I1665J833D01*
G01X1010403Y243928D01*
G03X1010530Y243818I1247J1311D01*
G01X1010842Y243569D01*
X1010844Y243567D01*
X1011014Y243432D01*
X1011095Y243369D01*
X1011118Y243351D01*
X1011138Y243336D01*
X1011224Y243268D01*
X1011225D01*
X1011251Y243247D01*
X1011400Y243131D01*
X1011424Y243113D01*
X1011434Y243104D01*
X1011913Y242726D01*
G02X1012204Y242125I-475J-601D01*
G01X1016141Y249999D02*
G02X1016546Y249021I-978J-978D01*
G02X1016299Y248425I-843J0D01*
G01X1016264Y248391D01*
G02X1015732Y248170I-533J532D01*
G01X1015583D01*
G02X1014870Y248466I1J1009D01*
G01X1014865Y248470D01*
G02X1014666Y248746I751J751D01*
G02X1014554Y249220I950J475D01*
G01Y264354D01*
X1014900Y264700D01*
G01X1010900Y264500D02*
X1010617Y264217D01*
Y245283D01*
G03X1010729Y244809I1062J1D01*
G03X1010928Y244533I950J475D01*
G01X1010933Y244529D01*
G03X1011646Y244233I714J713D01*
G01X1011795D01*
G03X1012327Y244454I-1J753D01*
G01X1012362Y244488D01*
G03X1012609Y245084I-596J596D01*
G03X1012204Y246062I-1383J0D01*
G01X1013600Y264700D02*
X1013754Y264546D01*
Y249221D01*
G03X1013950Y248388I1862J-1D01*
G03X1014335Y247869I1665J833D01*
G01X1014340Y247865D01*
G03X1014467Y247755I1247J1311D01*
G01X1014779Y247506D01*
X1014781Y247504D01*
X1014951Y247369D01*
X1015032Y247306D01*
X1015055Y247288D01*
X1015075Y247273D01*
X1015161Y247205D01*
X1015162D01*
X1015188Y247184D01*
X1015337Y247068D01*
X1015361Y247050D01*
X1015371Y247041D01*
X1015850Y246663D01*
G02X1016141Y246062I-475J-601D01*
G54D14*
X300500Y715613D03*
G54D24*
G01X145579Y-328699D02*
Y-346199D01*
X154313D01*
G01X167446Y-334533D02*
Y-346199D01*
G01Y-329866D02*
X167009Y-329574D01*
Y-328991D01*
X167446Y-328699D01*
X167883Y-328991D01*
Y-329574D01*
X167446Y-329866D01*
G01X181889Y-350574D02*
X183418Y-351741D01*
X185164Y-352032D01*
X186692Y-351741D01*
X188003Y-350283D01*
X188876Y-348241D01*
Y-334533D01*
G01Y-336866D02*
X188003Y-335699D01*
X186692Y-334824D01*
X185164Y-334533D01*
X183418Y-335116D01*
X182326Y-336282D01*
X181452Y-338324D01*
X181016Y-340366D01*
X181234Y-342116D01*
X182108Y-344158D01*
X183418Y-345616D01*
X185164Y-346199D01*
X186474Y-345907D01*
X188003Y-344741D01*
X188876Y-343575D01*
G01X198734Y-346199D02*
Y-328699D01*
G01Y-337157D02*
X199826Y-335699D01*
X200918Y-334824D01*
X202664Y-334533D01*
X203974Y-334824D01*
X205503Y-335991D01*
X206158Y-337741D01*
Y-346199D01*
G01X219946Y-328699D02*
Y-346199D01*
G01X216889Y-334533D02*
X223003D01*
G01X233734Y-346199D02*
Y-334533D01*
G01Y-337449D02*
X234608Y-335991D01*
X235918Y-334824D01*
X237664Y-334533D01*
X239192Y-334824D01*
X240503Y-335991D01*
X241158Y-338032D01*
Y-346199D01*
G01X254946Y-334533D02*
Y-346199D01*
G01Y-329866D02*
X254509Y-329574D01*
Y-328991D01*
X254946Y-328699D01*
X255383Y-328991D01*
Y-329574D01*
X254946Y-329866D01*
G01X268734Y-346199D02*
Y-334533D01*
G01Y-337449D02*
X269608Y-335991D01*
X270918Y-334824D01*
X272664Y-334533D01*
X274192Y-334824D01*
X275503Y-335991D01*
X276158Y-338032D01*
Y-346199D01*
G01X286889Y-350574D02*
X288418Y-351741D01*
X290164Y-352032D01*
X291692Y-351741D01*
X293003Y-350283D01*
X293876Y-348241D01*
Y-334533D01*
G01Y-336866D02*
X293003Y-335699D01*
X291692Y-334824D01*
X290164Y-334533D01*
X288418Y-335116D01*
X287326Y-336282D01*
X286452Y-338324D01*
X286016Y-340366D01*
X286234Y-342116D01*
X287108Y-344158D01*
X288418Y-345616D01*
X290164Y-346199D01*
X291474Y-345907D01*
X293003Y-344741D01*
X293876Y-343575D01*
G01X320579Y-346199D02*
Y-328699D01*
X325819D01*
X327566Y-329574D01*
X328876Y-331616D01*
X329313Y-333949D01*
X328876Y-336282D01*
X327784Y-338032D01*
X325819Y-338908D01*
X320579D01*
G01X346813Y-346199D02*
X338079D01*
Y-328699D01*
X346813D01*
G01X343319Y-337157D02*
X338079D01*
G01X361692Y-336866D02*
X362566Y-335991D01*
X363221Y-334533D01*
X363658Y-332490D01*
X363221Y-330741D01*
X362348Y-329574D01*
X360819Y-328699D01*
X354924D01*
Y-346199D01*
X362129D01*
X363658Y-345033D01*
X364531Y-343282D01*
X364968Y-341241D01*
X364531Y-339199D01*
X363221Y-337449D01*
X361692Y-336866D01*
X354924D01*
G01X390579Y-346199D02*
Y-328699D01*
X395819D01*
X397566Y-329574D01*
X398876Y-331616D01*
X399313Y-333949D01*
X398876Y-336282D01*
X397784Y-338032D01*
X395819Y-338908D01*
X390579D01*
G01X406769Y-346199D02*
Y-328699D01*
X412446Y-343282D01*
X418123Y-328699D01*
Y-346199D01*
G01X434749Y-330158D02*
X433439Y-329282D01*
X431911Y-328699D01*
X430164D01*
X428199Y-329574D01*
X426671Y-331032D01*
X425579Y-332783D01*
X424706Y-335699D01*
X424487Y-338324D01*
X424924Y-340949D01*
X425579Y-342699D01*
X426889Y-344449D01*
X428418Y-345616D01*
X429946Y-346199D01*
X431474D01*
X433003Y-345616D01*
X434313Y-344741D01*
X435405Y-343575D01*
G01X460579Y-346199D02*
Y-328699D01*
X465819D01*
X467566Y-329574D01*
X468876Y-331616D01*
X469313Y-333949D01*
X468876Y-336282D01*
X467784Y-338032D01*
X465819Y-338908D01*
X460579D01*
G01X476987Y-328699D02*
X482446Y-346199D01*
X487905Y-328699D01*
G01X499946D02*
Y-346199D01*
G01X494924Y-328699D02*
X504968D01*
G01X284269Y-301199D02*
Y-283699D01*
X289946Y-298282D01*
X295623Y-283699D01*
Y-301199D01*
G01X307446D02*
X306136Y-300907D01*
X304826Y-299741D01*
X303952Y-297699D01*
X303516Y-295366D01*
X303952Y-293032D01*
X304826Y-290991D01*
X306136Y-289824D01*
X307446Y-289533D01*
X308756Y-289824D01*
X310066Y-290991D01*
X310939Y-293032D01*
X311158Y-295366D01*
X310939Y-297699D01*
X310066Y-299741D01*
X308756Y-300907D01*
X307446Y-301199D01*
G01X328876Y-283699D02*
Y-301199D01*
G01Y-298575D02*
X328003Y-300033D01*
X326692Y-300907D01*
X325164Y-301199D01*
X323418Y-300616D01*
X322108Y-299158D01*
X321234Y-297408D01*
X321016Y-295366D01*
X321234Y-293324D01*
X322108Y-291574D01*
X323418Y-290116D01*
X325164Y-289533D01*
X326692Y-289824D01*
X327784Y-290408D01*
X328876Y-291574D01*
G01X339171Y-293324D02*
X346158D01*
X345503Y-291282D01*
X344411Y-290116D01*
X342883Y-289533D01*
X341354Y-289824D01*
X340044Y-290699D01*
X339171Y-292741D01*
X338734Y-294491D01*
Y-296241D01*
X339171Y-297991D01*
X340263Y-299741D01*
X341573Y-300907D01*
X343101Y-301199D01*
X344629Y-300616D01*
X346158Y-298866D01*
G01X359946Y-301199D02*
Y-283699D01*
G01X556346Y-346199D02*
Y-328699D01*
X553726Y-332199D01*
G01Y-346199D02*
X558966D01*
G01X569043Y-343575D02*
X570352Y-345033D01*
X571881Y-345907D01*
X573846Y-346199D01*
X575811Y-345616D01*
X577339Y-344449D01*
X578431Y-342408D01*
X578649Y-340074D01*
X578213Y-337741D01*
X577121Y-336282D01*
X575592Y-335116D01*
X574064Y-334824D01*
X572536Y-335116D01*
X570571Y-336282D01*
X571226Y-328699D01*
X577121D01*
G01X591346Y-346199D02*
Y-328699D01*
X588726Y-332199D01*
G01Y-346199D02*
X593966D01*
G01X608846Y-328699D02*
X607099Y-329282D01*
X605789Y-330741D01*
X604916Y-332490D01*
X604261Y-334824D01*
X604043Y-337449D01*
X604261Y-340074D01*
X604916Y-342408D01*
X605789Y-344158D01*
X607099Y-345616D01*
X608846Y-346199D01*
X610592Y-345616D01*
X611903Y-344158D01*
X612776Y-342408D01*
X613431Y-340074D01*
X613649Y-337449D01*
X613431Y-334824D01*
X612776Y-332490D01*
X611903Y-330741D01*
X610592Y-329282D01*
X608846Y-328699D01*
G01X621543Y-343575D02*
X622852Y-345033D01*
X624381Y-345907D01*
X626346Y-346199D01*
X628311Y-345616D01*
X629839Y-344449D01*
X630931Y-342408D01*
X631149Y-340074D01*
X630713Y-337741D01*
X629621Y-336282D01*
X628092Y-335116D01*
X626564Y-334824D01*
X625036Y-335116D01*
X623071Y-336282D01*
X623726Y-328699D01*
X629621D01*
G01X543229Y-301199D02*
Y-283699D01*
X548469D01*
X550216Y-284574D01*
X551526Y-286616D01*
X551963Y-288949D01*
X551526Y-291282D01*
X550434Y-293032D01*
X548469Y-293908D01*
X543229D01*
G01X569899Y-285158D02*
X568589Y-284282D01*
X567061Y-283699D01*
X565314D01*
X563349Y-284574D01*
X561821Y-286032D01*
X560729Y-287783D01*
X559856Y-290699D01*
X559637Y-293324D01*
X560074Y-295949D01*
X560729Y-297699D01*
X562039Y-299449D01*
X563568Y-300616D01*
X565096Y-301199D01*
X566624D01*
X568153Y-300616D01*
X569463Y-299741D01*
X570555Y-298575D01*
G01X584342Y-291866D02*
X585216Y-290991D01*
X585871Y-289533D01*
X586308Y-287490D01*
X585871Y-285741D01*
X584998Y-284574D01*
X583469Y-283699D01*
X577574D01*
Y-301199D01*
X584779D01*
X586308Y-300033D01*
X587181Y-298282D01*
X587618Y-296241D01*
X587181Y-294199D01*
X585871Y-292449D01*
X584342Y-291866D01*
X577574D01*
G01X593546Y-307032D02*
X606646D01*
G01X612574Y-301199D02*
Y-283699D01*
X622618Y-301199D01*
Y-283699D01*
G01X635096Y-301199D02*
X633349Y-300907D01*
X631821Y-299741D01*
X630511Y-297991D01*
X629637Y-295949D01*
X629201Y-293616D01*
Y-291282D01*
X629637Y-288949D01*
X630511Y-286907D01*
X631821Y-285158D01*
X633349Y-283991D01*
X635096Y-283699D01*
X636842Y-283991D01*
X638371Y-285158D01*
X639681Y-286907D01*
X640555Y-288949D01*
X640991Y-291282D01*
Y-293616D01*
X640555Y-295949D01*
X639681Y-297991D01*
X638371Y-299741D01*
X636842Y-300907D01*
X635096Y-301199D01*
G01X685937Y-283699D02*
X691396Y-301199D01*
X696855Y-283699D01*
G01X713263Y-301199D02*
X704529D01*
Y-283699D01*
X713263D01*
G01X709769Y-292157D02*
X704529D01*
G01X722029Y-301199D02*
Y-283699D01*
X727488D01*
X729234Y-284574D01*
X730326Y-285741D01*
X730763Y-288074D01*
X730326Y-290408D01*
X729016Y-291866D01*
X727488Y-292741D01*
X722029D01*
G01X727488D02*
X730763Y-301199D01*
G01X743896Y-301782D02*
X743459Y-301491D01*
Y-300907D01*
X743896Y-300616D01*
X744333Y-300907D01*
Y-301491D01*
X743896Y-301782D01*
G01X717646Y-346199D02*
Y-328699D01*
X715026Y-332199D01*
G01Y-346199D02*
X720266D01*
G01X819479Y-283699D02*
Y-301199D01*
X828213D01*
G01X845276D02*
Y-289533D01*
G01Y-291574D02*
X844403Y-290408D01*
X843092Y-289824D01*
X841564Y-289533D01*
X840036Y-290116D01*
X838726Y-291282D01*
X837852Y-293032D01*
X837416Y-295366D01*
X837852Y-297699D01*
X838726Y-299449D01*
X840036Y-300616D01*
X841564Y-301199D01*
X843092Y-300907D01*
X844403Y-300033D01*
X845276Y-298866D01*
G01X854261Y-306449D02*
X855571Y-307032D01*
X857318Y-306449D01*
X858409Y-305283D01*
X859283Y-303824D01*
X860592Y-299158D01*
X863431Y-289533D01*
G01X856444D02*
X860592Y-299158D01*
G01X873071Y-293324D02*
X880058D01*
X879403Y-291282D01*
X878311Y-290116D01*
X876783Y-289533D01*
X875254Y-289824D01*
X873944Y-290699D01*
X873071Y-292741D01*
X872634Y-294491D01*
Y-296241D01*
X873071Y-297991D01*
X874163Y-299741D01*
X875473Y-300907D01*
X877001Y-301199D01*
X878529Y-300616D01*
X880058Y-298866D01*
G01X890789Y-301199D02*
Y-289533D01*
G01Y-291866D02*
X891881Y-290699D01*
X892973Y-289824D01*
X894501Y-289533D01*
X895592Y-289824D01*
X896903Y-290699D01*
G01X845729Y-328699D02*
Y-346199D01*
X854463D01*
G01X862793Y-342699D02*
X864102Y-344741D01*
X865849Y-345907D01*
X867814Y-346199D01*
X869561Y-345907D01*
X871308Y-344449D01*
X872399Y-342699D01*
X872618Y-340949D01*
X872181Y-338908D01*
X870653Y-337449D01*
X869124Y-336866D01*
X867159D01*
G01X869124D02*
X870434Y-335991D01*
X871526Y-334533D01*
X871963Y-332783D01*
X871526Y-331032D01*
X870434Y-329574D01*
X868469Y-328699D01*
X866504Y-328991D01*
X864539Y-330158D01*
G01X959846Y-328699D02*
X962902Y-346199D01*
X966396Y-328699D01*
X969889Y-346199D01*
X972946Y-328699D01*
G01X979529Y-346199D02*
Y-328699D01*
X984769D01*
X986516Y-329574D01*
X987826Y-331616D01*
X988263Y-333949D01*
X987826Y-336282D01*
X986734Y-338032D01*
X984769Y-338908D01*
X979529D01*
G01X996811Y-346199D02*
Y-328699D01*
G01X1005981D02*
Y-346199D01*
G01Y-337449D02*
X996811D01*
G01X1016058Y-340366D02*
X1021734D01*
G01X1031593Y-346199D02*
Y-328699D01*
G01X1039889D02*
X1031593Y-339491D01*
G01X1041199Y-346199D02*
X1035304Y-334533D01*
G01X1058263Y-346199D02*
X1049529D01*
Y-328699D01*
X1058263D01*
G01X1054769Y-337157D02*
X1049529D01*
G01X1066374Y-346199D02*
Y-328699D01*
X1076418Y-346199D01*
Y-328699D01*
G01X1083874Y-346199D02*
Y-328699D01*
X1093918Y-346199D01*
Y-328699D01*
G01X961593Y-301199D02*
Y-283699D01*
X965959D01*
X967706Y-284574D01*
X969016Y-285741D01*
X970108Y-287490D01*
X970981Y-289533D01*
X971199Y-292449D01*
X970981Y-295366D01*
X970108Y-297408D01*
X969016Y-299158D01*
X967706Y-300324D01*
X965959Y-301199D01*
X961593D01*
G01X980621Y-293324D02*
X987608D01*
X986953Y-291282D01*
X985861Y-290116D01*
X984333Y-289533D01*
X982804Y-289824D01*
X981494Y-290699D01*
X980621Y-292741D01*
X980184Y-294491D01*
Y-296241D01*
X980621Y-297991D01*
X981713Y-299741D01*
X983023Y-300907D01*
X984551Y-301199D01*
X986079Y-300616D01*
X987608Y-298866D01*
G01X998121Y-299158D02*
X999213Y-300324D01*
X1000741Y-301199D01*
X1002051D01*
X1003361Y-300616D01*
X1004234Y-299741D01*
X1004671Y-298575D01*
X1004453Y-296824D01*
X1003579Y-295949D01*
X999649Y-294199D01*
X998776Y-292157D01*
X999213Y-290699D01*
X1000086Y-289824D01*
X1001396Y-289533D01*
X1002706Y-289824D01*
X1004016Y-290699D01*
G01X1018896Y-289533D02*
Y-301199D01*
G01Y-284866D02*
X1018459Y-284574D01*
Y-283991D01*
X1018896Y-283699D01*
X1019333Y-283991D01*
Y-284574D01*
X1018896Y-284866D01*
G01X1033339Y-305574D02*
X1034868Y-306741D01*
X1036614Y-307032D01*
X1038142Y-306741D01*
X1039453Y-305283D01*
X1040326Y-303241D01*
Y-289533D01*
G01Y-291866D02*
X1039453Y-290699D01*
X1038142Y-289824D01*
X1036614Y-289533D01*
X1034868Y-290116D01*
X1033776Y-291282D01*
X1032902Y-293324D01*
X1032466Y-295366D01*
X1032684Y-297116D01*
X1033558Y-299158D01*
X1034868Y-300616D01*
X1036614Y-301199D01*
X1037924Y-300907D01*
X1039453Y-299741D01*
X1040326Y-298575D01*
G01X1050184Y-301199D02*
Y-289533D01*
G01Y-292449D02*
X1051058Y-290991D01*
X1052368Y-289824D01*
X1054114Y-289533D01*
X1055642Y-289824D01*
X1056953Y-290991D01*
X1057608Y-293032D01*
Y-301199D01*
G01X1068121Y-293324D02*
X1075108D01*
X1074453Y-291282D01*
X1073361Y-290116D01*
X1071833Y-289533D01*
X1070304Y-289824D01*
X1068994Y-290699D01*
X1068121Y-292741D01*
X1067684Y-294491D01*
Y-296241D01*
X1068121Y-297991D01*
X1069213Y-299741D01*
X1070523Y-300907D01*
X1072051Y-301199D01*
X1073579Y-300616D01*
X1075108Y-298866D01*
G01X1085839Y-301199D02*
Y-289533D01*
G01Y-291866D02*
X1086931Y-290699D01*
X1088023Y-289824D01*
X1089551Y-289533D01*
X1090642Y-289824D01*
X1091953Y-290699D01*
G01X1132596Y-346199D02*
Y-328699D01*
X1129976Y-332199D01*
G01Y-346199D02*
X1135216D01*
G01X1150096D02*
Y-328699D01*
X1147476Y-332199D01*
G01Y-346199D02*
X1152716D01*
G01X1163666Y-346782D02*
X1171526Y-328699D01*
G01X1185096Y-346199D02*
Y-328699D01*
X1182476Y-332199D01*
G01Y-346199D02*
X1187716D01*
G01X1198448Y-338908D02*
X1199976Y-336866D01*
X1201286Y-335699D01*
X1203033Y-335116D01*
X1204561Y-335699D01*
X1205653Y-336866D01*
X1206526Y-338616D01*
X1206744Y-340657D01*
X1206526Y-342408D01*
X1205653Y-344158D01*
X1204342Y-345616D01*
X1202814Y-346199D01*
X1201068Y-345616D01*
X1199539Y-343866D01*
X1198666Y-341241D01*
X1198448Y-338324D01*
X1198884Y-334533D01*
X1199539Y-332490D01*
X1200631Y-330449D01*
X1202159Y-328991D01*
X1203688Y-328699D01*
X1205216Y-329282D01*
X1206308Y-330741D01*
G01X1216166Y-346782D02*
X1224026Y-328699D01*
G01X1233448Y-331616D02*
X1234758Y-329866D01*
X1236286Y-328991D01*
X1238033Y-328699D01*
X1240216Y-329282D01*
X1241744Y-330741D01*
X1242181Y-332490D01*
X1241963Y-334241D01*
X1241089Y-335699D01*
X1236723Y-338616D01*
X1234758Y-340657D01*
X1233448Y-343575D01*
X1233011Y-346199D01*
X1242181D01*
G01X1255096Y-328699D02*
X1253349Y-329282D01*
X1252039Y-330741D01*
X1251166Y-332490D01*
X1250511Y-334824D01*
X1250293Y-337449D01*
X1250511Y-340074D01*
X1251166Y-342408D01*
X1252039Y-344158D01*
X1253349Y-345616D01*
X1255096Y-346199D01*
X1256842Y-345616D01*
X1258153Y-344158D01*
X1259026Y-342408D01*
X1259681Y-340074D01*
X1259899Y-337449D01*
X1259681Y-334824D01*
X1259026Y-332490D01*
X1258153Y-330741D01*
X1256842Y-329282D01*
X1255096Y-328699D01*
G01X1272596Y-346199D02*
Y-328699D01*
X1269976Y-332199D01*
G01Y-346199D02*
X1275216D01*
G01X1285948Y-338908D02*
X1287476Y-336866D01*
X1288786Y-335699D01*
X1290533Y-335116D01*
X1292061Y-335699D01*
X1293153Y-336866D01*
X1294026Y-338616D01*
X1294244Y-340657D01*
X1294026Y-342408D01*
X1293153Y-344158D01*
X1291842Y-345616D01*
X1290314Y-346199D01*
X1288568Y-345616D01*
X1287039Y-343866D01*
X1286166Y-341241D01*
X1285948Y-338324D01*
X1286384Y-334533D01*
X1287039Y-332490D01*
X1288131Y-330449D01*
X1289659Y-328991D01*
X1291188Y-328699D01*
X1292716Y-329282D01*
X1293808Y-330741D01*
G01X1180293Y-301199D02*
Y-283699D01*
X1184659D01*
X1186406Y-284574D01*
X1187716Y-285741D01*
X1188808Y-287490D01*
X1189681Y-289533D01*
X1189899Y-292449D01*
X1189681Y-295366D01*
X1188808Y-297408D01*
X1187716Y-299158D01*
X1186406Y-300324D01*
X1184659Y-301199D01*
X1180293D01*
G01X1206526D02*
Y-289533D01*
G01Y-291574D02*
X1205653Y-290408D01*
X1204342Y-289824D01*
X1202814Y-289533D01*
X1201286Y-290116D01*
X1199976Y-291282D01*
X1199102Y-293032D01*
X1198666Y-295366D01*
X1199102Y-297699D01*
X1199976Y-299449D01*
X1201286Y-300616D01*
X1202814Y-301199D01*
X1204342Y-300907D01*
X1205653Y-300033D01*
X1206526Y-298866D01*
G01X1220096Y-283699D02*
Y-301199D01*
G01X1217039Y-289533D02*
X1223153D01*
G01X1234321Y-293324D02*
X1241308D01*
X1240653Y-291282D01*
X1239561Y-290116D01*
X1238033Y-289533D01*
X1236504Y-289824D01*
X1235194Y-290699D01*
X1234321Y-292741D01*
X1233884Y-294491D01*
Y-296241D01*
X1234321Y-297991D01*
X1235413Y-299741D01*
X1236723Y-300907D01*
X1238251Y-301199D01*
X1239779Y-300616D01*
X1241308Y-298866D01*
G01X1012177Y-2940D02*
X1009277Y-40D01*
X1007565D01*
X1002085Y-5520D01*
X973828D01*
X964163Y-15185D01*
X506910D01*
X474884Y16841D01*
X474671D01*
X469616Y16842D01*
X362528Y123930D01*
Y123931D01*
G01X1019859Y-7642D02*
X1020044Y-7457D01*
Y4196D01*
X1013902Y10338D01*
X975248D01*
X950925Y-13985D01*
X507408D01*
X474815Y18608D01*
X470663D01*
X363440Y125831D01*
X360626D01*
X358917Y124122D01*
G01X1008353Y-1940D02*
X1003573Y-6720D01*
X974326D01*
X964661Y-16385D01*
X506129D01*
X474596Y15148D01*
X469247D01*
X363627Y120768D01*
X358423D01*
X355069Y124122D01*
G54D15*
X473231Y235560D03*
Y274930D03*
G54D25*
G01X352600Y128200D02*
X351183Y129617D01*
X348471D01*
X346300Y131788D01*
Y185529D01*
X352700Y191929D01*
Y228831D01*
X325731Y255800D01*
X304083D01*
X289983Y241700D01*
X186671D01*
X176971Y251400D01*
X161229D01*
X158729Y248900D01*
X139729D01*
X132629Y241800D01*
X74971D01*
X63419Y253352D01*
X36253D01*
X33300Y250399D01*
X27782D01*
X26600Y249217D01*
G01X352600Y132537D02*
X351680Y131617D01*
X349300D01*
X348300Y132617D01*
Y184700D01*
X354700Y191100D01*
Y229660D01*
X326560Y257800D01*
X303254D01*
X289154Y243700D01*
X187500D01*
X177800Y253400D01*
X160400D01*
X157900Y250900D01*
X138900D01*
X131800Y243800D01*
X75800D01*
X64248Y255352D01*
X35424D01*
X32471Y252399D01*
X27783D01*
X26600Y253582D01*
G01X62400Y624500D02*
Y622822D01*
X11340Y571762D01*
Y433990D01*
X24123Y421207D01*
Y409061D01*
X24122Y409060D01*
Y407818D01*
X49549Y382391D01*
X49550Y382001D01*
Y377733D01*
X73773Y353510D01*
X84756D01*
X87465Y350801D01*
X90689D01*
X104040Y337450D01*
X107484D01*
X110784Y334150D01*
X116151D01*
X116901Y334900D01*
X167675D01*
X169791Y332784D01*
X212800D01*
X214270Y331314D01*
X256285D01*
X259641Y334670D01*
X273959D01*
X286589Y322040D01*
X298540D01*
X301910Y325410D01*
X319990D01*
X325502Y319898D01*
X343370D01*
X347568Y315700D01*
X368900D01*
G01X134800Y329600D02*
X101001D01*
X96550Y334051D01*
Y336778D01*
X87078Y346250D01*
X85650D01*
X83200Y348700D01*
X71726D01*
X53182Y367244D01*
X41371D01*
X38016Y370599D01*
Y372133D01*
X40368Y374485D01*
Y377683D01*
X29051Y389000D01*
X25350D01*
G01X63300Y634800D02*
X64250Y633850D01*
Y622450D01*
X12840Y571040D01*
Y434612D01*
X25623Y421829D01*
Y408439D01*
X51048Y383014D01*
X51050Y382238D01*
Y381467D01*
X74205Y358312D01*
Y356378D01*
X75572Y355011D01*
X85389D01*
X88099Y352301D01*
X91312D01*
X104663Y338950D01*
X108106D01*
X109206Y337850D01*
X114467D01*
X115217Y337100D01*
Y337098D01*
X167713D01*
X170321Y334490D01*
X213216D01*
X214892Y332814D01*
X255663D01*
X259019Y336170D01*
X274581D01*
X287211Y323540D01*
X297918D01*
X301288Y326910D01*
X320612D01*
X326124Y321398D01*
X365819D01*
X374100Y313117D01*
Y303761D01*
X375048Y302809D01*
Y302801D01*
X375340Y302509D01*
X375925Y301922D01*
X377220Y300626D01*
X377639Y300206D01*
X383700Y294146D01*
Y203300D01*
X383600Y203200D01*
G01X65350Y690356D02*
X9840Y634846D01*
Y433368D01*
X22623Y420585D01*
Y409683D01*
X22622Y409682D01*
Y407196D01*
X22623Y407195D01*
Y404390D01*
X37450Y389563D01*
Y388733D01*
X38533Y387650D01*
X39363D01*
X47105Y379908D01*
Y378056D01*
X73151Y352010D01*
X84134D01*
X86843Y349301D01*
X90067D01*
X106718Y332650D01*
X117105D01*
X117855Y333400D01*
X166457D01*
X169952Y329905D01*
X189365D01*
G01X919486Y13778D02*
X916236Y17028D01*
X893650D01*
X883622Y7000D01*
X879691D01*
X868144Y-4547D01*
X810845D01*
X810842Y-4544D01*
X797095Y9200D01*
X777550D01*
X775957Y7607D01*
X773565D01*
X772482Y8690D01*
X770948D01*
X767567Y5309D01*
X742358D01*
X739849Y2800D01*
X735800D01*
X733175Y5425D01*
X726341D01*
X724785Y3869D01*
X701250D01*
X697205Y7914D01*
X520277D01*
X491526Y36649D01*
X477806D01*
X378485Y135970D01*
Y189983D01*
X388900Y200398D01*
Y281990D01*
X388899Y293479D01*
Y295315D01*
X380825Y303389D01*
X380406Y303809D01*
X379549Y304666D01*
Y304668D01*
X378600Y305621D01*
Y315356D01*
X368057Y325899D01*
X365756D01*
X351165Y340490D01*
X231010D01*
X228965Y342535D01*
X210657D01*
X208972Y340850D01*
X175600D01*
X171020Y345430D01*
X117780D01*
X117779Y345429D01*
X114049D01*
X108878Y350600D01*
X104384D01*
X94833Y360151D01*
X92248D01*
X78879Y373520D01*
X71174D01*
X64214Y380480D01*
Y384155D01*
X40217Y408152D01*
Y408691D01*
X40216Y408692D01*
Y409934D01*
X40217Y409935D01*
Y410238D01*
X33489Y416966D01*
Y427733D01*
X20989Y440233D01*
Y519610D01*
X49380Y548001D01*
X50317D01*
X59316Y557000D01*
X74000D01*
G01X35709Y426942D02*
Y428091D01*
X25570Y438230D01*
Y474809D01*
X22489Y477890D01*
Y518988D01*
X50002Y546501D01*
X51893D01*
X59611Y554219D01*
X73836D01*
X76407Y556790D01*
X77807D01*
X81304Y560287D01*
Y568618D01*
X84076Y571390D01*
Y577924D01*
X84226D01*
G01X77400Y550400D02*
X75731Y552069D01*
X59583D01*
X52515Y545001D01*
X50624D01*
X23990Y518367D01*
Y478511D01*
X27070Y475431D01*
Y438852D01*
X37559Y428363D01*
Y419893D01*
X37558Y419892D01*
Y418650D01*
X37557Y418649D01*
Y417407D01*
X43217Y411747D01*
Y409396D01*
X67214Y385399D01*
Y382615D01*
X68365Y381464D01*
G01X111900Y344200D02*
X111837D01*
X110737Y345300D01*
X107294D01*
X93943Y358651D01*
X90730D01*
X81881Y367500D01*
X74939D01*
X62714Y379725D01*
Y383533D01*
X38717Y407530D01*
Y408069D01*
X38715Y408071D01*
Y409313D01*
X38716Y409314D01*
Y409616D01*
X31989Y416343D01*
Y427111D01*
X19489Y439611D01*
Y520232D01*
X48758Y549501D01*
X49695D01*
X59124Y558930D01*
X63000D01*
G01X69100Y549200D02*
X67731Y550569D01*
X60205D01*
X53137Y543501D01*
X51246D01*
X25600Y517855D01*
Y479023D01*
X28570Y476053D01*
Y439474D01*
X39059Y428985D01*
Y418027D01*
X44717Y412369D01*
X46379D01*
X46448Y412300D01*
X47025Y411722D01*
X48363Y410385D01*
X67090Y391658D01*
Y390247D01*
X70171Y387166D01*
Y381975D01*
X75624Y376522D01*
X80701D01*
X93923Y363300D01*
X94038D01*
X94039Y363299D01*
X95281D01*
X95282Y363300D01*
X95928D01*
X105628Y353600D01*
X110122D01*
X115293Y348429D01*
X116535D01*
X116536Y348430D01*
X173178D01*
X176674Y344934D01*
G01X65381Y548719D02*
X60478D01*
X53760Y542001D01*
X51868D01*
X27100Y517233D01*
Y479645D01*
X30070Y476675D01*
Y452030D01*
X35400Y446700D01*
Y434766D01*
X40560Y429606D01*
Y418899D01*
X45590Y413869D01*
X47003D01*
X47242Y413630D01*
X47511Y413360D01*
X48087Y412783D01*
X49424Y411447D01*
X58671Y402200D01*
X61400Y399470D01*
X68590Y392280D01*
Y390869D01*
X93650Y365809D01*
X93651D01*
X94660Y364800D01*
X96550D01*
X106250Y355100D01*
X110744D01*
X115914Y349930D01*
X177154D01*
X180300Y346784D01*
X205858D01*
X208879Y349805D01*
X212536D01*
G01X73700Y549300D02*
X70950Y546550D01*
X61675D01*
X61674Y546551D01*
X60432D01*
X54381Y540500D01*
X53733D01*
X53732Y540501D01*
X52490D01*
X28600Y516611D01*
Y480267D01*
X31570Y477297D01*
Y453057D01*
X37600Y447027D01*
Y434688D01*
X44000Y428288D01*
Y420919D01*
X46950Y417969D01*
Y416048D01*
X47715Y415283D01*
Y415281D01*
X47718Y415278D01*
X48574Y414420D01*
X52144Y410850D01*
X59732Y403261D01*
X62461Y400531D01*
X70090Y392902D01*
Y391491D01*
X94272Y367309D01*
X94273D01*
X95082Y366500D01*
X96972D01*
X106872Y356600D01*
X111366D01*
X116183Y351783D01*
X177916D01*
X181356Y348343D01*
X195469D01*
X195940Y348814D01*
G01X73700Y542600D02*
X71250Y545050D01*
X61053D01*
X55002Y538999D01*
X54354D01*
X54353Y539000D01*
X53111D01*
X30100Y515989D01*
Y480889D01*
X33070Y477919D01*
Y473630D01*
X35750Y470950D01*
Y467199D01*
X33400Y464849D01*
Y453349D01*
X39561Y447188D01*
Y434849D01*
X45930Y428480D01*
Y421300D01*
X48450Y418780D01*
Y416670D01*
X49216Y415904D01*
Y415902D01*
X49717Y415400D01*
X51617Y413500D01*
X60793Y404322D01*
X63522Y401592D01*
X71590Y393524D01*
Y392113D01*
X94893Y368810D01*
X96135D01*
X96136Y368811D01*
X101330D01*
X101341Y368800D01*
X116726Y353500D01*
X116864Y353499D01*
X118106D01*
X118107Y353500D01*
X178800D01*
X182457Y349843D01*
X194088D01*
X196529Y352284D01*
G01X29300Y539850D02*
Y574978D01*
X62611Y608289D01*
G01X21250Y742650D02*
X24250Y739650D01*
Y722550D01*
X22810Y721110D01*
Y709160D01*
X31550Y700420D01*
X39690D01*
X42910Y697200D01*
X63300D01*
G01X35300Y303100D02*
Y295800D01*
X48150Y282950D01*
X100732D01*
X102499Y281183D01*
G01X39000Y299500D02*
Y297300D01*
X43300Y293000D01*
X63983D01*
X65383Y294400D01*
X77617D01*
X79017Y293000D01*
X94800D01*
X95700Y293900D01*
G01X31700Y314700D02*
X36200Y310200D01*
X39670D01*
X42720Y313250D01*
X47738D01*
X47739Y313251D01*
X49395D01*
X49396Y313250D01*
X60650D01*
X61907Y314507D01*
X63563D01*
X63564Y314506D01*
X89423D01*
X104587Y299342D01*
X108712D01*
X110470Y301100D01*
X165172D01*
X166600Y302528D01*
Y303837D01*
X166087Y304350D01*
G01X31662Y303262D02*
X36600Y308200D01*
X40499D01*
X43549Y311250D01*
X61479D01*
X62735Y312506D01*
X88594D01*
X103758Y297342D01*
X109541D01*
X111299Y299100D01*
X166001D01*
X168600Y301699D01*
Y303094D01*
X170062Y304556D01*
G01X61800Y306900D02*
X60900Y306000D01*
X41900D01*
X38800Y302900D01*
G01X38518Y376916D02*
X37200Y375598D01*
Y373499D01*
X35600Y371899D01*
Y369301D01*
X39655Y365244D01*
X49662D01*
X58946Y355960D01*
Y355897D01*
X63543Y351300D01*
X67003D01*
X71403Y346900D01*
X71715D01*
X77315Y341300D01*
X88834D01*
X95050Y335084D01*
Y333279D01*
X100629Y327700D01*
X136502D01*
X139202Y330400D01*
X164104D01*
X166920Y327584D01*
X174006D01*
X179790Y321800D01*
X184617D01*
X188210Y318207D01*
X196668D01*
X199291Y320830D01*
X204914D01*
X206900Y322816D01*
Y324321D01*
X205840Y325381D01*
G01X34153Y376916D02*
X35200Y375869D01*
Y374328D01*
X33600Y372728D01*
Y368472D01*
X38826Y363244D01*
X48833D01*
X56946Y355131D01*
Y355068D01*
X62714Y349300D01*
X66174D01*
X70574Y344900D01*
X70886D01*
X76486Y339300D01*
X88005D01*
X93050Y334255D01*
Y332450D01*
X99800Y325700D01*
X137331D01*
X140031Y328400D01*
X163275D01*
X166091Y325584D01*
X173177D01*
X178961Y319800D01*
X183788D01*
X187381Y316207D01*
X197497D01*
X200120Y318830D01*
X205743D01*
X208900Y321987D01*
Y324204D01*
X209000D01*
X210177Y325381D01*
G01X39866Y371366D02*
X42488Y368744D01*
X53895D01*
X72129Y350510D01*
X83512D01*
X86221Y347801D01*
X87649D01*
X98050Y337400D01*
Y334849D01*
X101749Y331150D01*
X117727D01*
X118477Y331900D01*
X165221D01*
X167687Y329434D01*
G01X267979Y342500D02*
X260600D01*
X256012Y347088D01*
X213088D01*
X209084Y343084D01*
X175907D01*
X175883Y343108D01*
X175692D01*
X171870Y346930D01*
X117158D01*
X117157Y346929D01*
X114671D01*
X109500Y352100D01*
X105006D01*
X95307Y361799D01*
X93417D01*
X93416Y361800D01*
X93200D01*
X79979Y375021D01*
X71795D01*
X65714Y381102D01*
Y384777D01*
X41717Y408774D01*
Y411125D01*
X35709Y417133D01*
Y426942D01*
G01X65800Y538900D02*
X62729D01*
X62629Y539000D01*
X59954D01*
X56452Y535498D01*
X54561D01*
X54559Y535496D01*
X54558D01*
X35789Y516727D01*
Y516726D01*
X33850Y514787D01*
Y482090D01*
X36571Y479369D01*
Y477713D01*
X36570Y477712D01*
Y475460D01*
X39570Y472460D01*
Y452130D01*
X43700Y448000D01*
Y439451D01*
X52717Y430434D01*
Y424126D01*
X52363Y423538D01*
X51950Y423125D01*
Y418121D01*
X52717Y417354D01*
Y417352D01*
X54093Y415976D01*
X63898Y406168D01*
X75090Y394976D01*
Y393564D01*
X87719Y380935D01*
X91555D01*
X100177Y372313D01*
X103001D01*
X118314Y357000D01*
X185103D01*
X185142Y356961D01*
X186798D01*
X186837Y357000D01*
X199374D01*
X203567Y352807D01*
X214776D01*
G01X61800Y537000D02*
X60783D01*
X57281Y533498D01*
X55390D01*
X55388Y533496D01*
X55387D01*
X37789Y515898D01*
Y515897D01*
X37788Y515896D01*
Y500822D01*
X37789Y500821D01*
Y486282D01*
X37790Y486281D01*
Y486280D01*
X40079Y483991D01*
Y477039D01*
X41570Y475548D01*
Y453136D01*
X51800Y442906D01*
Y442905D01*
X54718Y439987D01*
Y431030D01*
X54717Y431029D01*
Y423570D01*
X53950Y422296D01*
Y418950D01*
X54718Y418182D01*
Y418181D01*
X55508Y417391D01*
X64684Y408213D01*
X65985Y406911D01*
X77090Y395806D01*
Y394393D01*
X81583Y389900D01*
X85419D01*
X100919Y374400D01*
X103743D01*
X114343Y363800D01*
X117872D01*
X122672Y359000D01*
X185932D01*
X185970Y358962D01*
G01X70000Y542500D02*
X68017D01*
X66517Y541000D01*
X59125D01*
X55624Y537499D01*
X53733D01*
X53730Y537496D01*
X53729D01*
X33789Y517556D01*
Y517555D01*
X31800Y515566D01*
Y481311D01*
X34570Y478541D01*
Y474631D01*
X37250Y471951D01*
Y466577D01*
X34900Y464227D01*
Y453971D01*
X41322Y447549D01*
Y439000D01*
X50717Y429605D01*
Y424722D01*
X49950Y423954D01*
Y417292D01*
X50716Y416526D01*
Y416524D01*
X51273Y415966D01*
X52678Y414561D01*
X61854Y405383D01*
X64584Y402653D01*
X65494Y401742D01*
X73090Y394146D01*
Y392735D01*
X95514Y370311D01*
X101952D01*
X101963Y370300D01*
X102185D01*
X117485Y355000D01*
X180610D01*
X182969Y352641D01*
G01X77300Y531238D02*
X76262Y530200D01*
X73300D01*
X70450Y527350D01*
X60328D01*
X59975Y526997D01*
X59974D01*
X59973Y526996D01*
X58081D01*
X53778Y522693D01*
Y522692D01*
X44290Y513204D01*
Y501088D01*
X44289Y501087D01*
Y488976D01*
X44290Y488975D01*
Y488974D01*
X45753Y487511D01*
X45754D01*
X49152Y484113D01*
Y481878D01*
X47962Y480688D01*
Y479154D01*
X58300Y468816D01*
Y445600D01*
X61218Y442682D01*
Y428336D01*
X61217Y428335D01*
Y426265D01*
X61219Y426263D01*
Y426222D01*
X64150Y423291D01*
Y419149D01*
X64543Y418756D01*
Y418755D01*
X66006Y417292D01*
X66007D01*
X77465Y405834D01*
X79119D01*
X89050Y395903D01*
Y395902D01*
X90513Y394439D01*
X90514D01*
X90900Y394053D01*
Y394052D01*
X92367Y392585D01*
X94511D01*
X101701Y385395D01*
Y383547D01*
X104348Y380900D01*
X106180D01*
X106269Y380811D01*
X108339D01*
X108340Y380812D01*
X108661D01*
X118521Y370952D01*
X137615D01*
X141054Y367513D01*
X149063D01*
X150998Y365578D01*
X166162D01*
X166281Y365697D01*
X204306D01*
X206747Y363256D01*
X213744D01*
X217000Y360000D01*
G01X77700Y538500D02*
X75000Y535800D01*
X72132D01*
X66182Y529850D01*
X59291D01*
X58938Y529497D01*
X57047D01*
X57046Y529496D01*
X57045D01*
X51278Y523729D01*
Y523728D01*
X41790Y514240D01*
X41789Y502125D01*
Y487940D01*
X41790Y487939D01*
Y487938D01*
X44717Y485011D01*
X44718D01*
X45462Y484267D01*
Y478118D01*
X50900Y472680D01*
Y449464D01*
X55800Y444564D01*
Y444563D01*
X57263Y443100D01*
X57264D01*
X58718Y441646D01*
Y429372D01*
X58717Y429371D01*
Y425229D01*
X58719Y425227D01*
Y425186D01*
X61650Y422255D01*
Y420733D01*
X61649Y420732D01*
Y418662D01*
X61650Y418661D01*
Y418113D01*
X62043Y417720D01*
Y417719D01*
X64970Y414792D01*
X64971D01*
X76430Y403333D01*
X78084D01*
X82850Y398567D01*
Y395233D01*
X84181Y393902D01*
X87075D01*
X90888Y390089D01*
X91806D01*
X91812Y390083D01*
X93476Y390084D01*
X99201Y384359D01*
Y382511D01*
X103312Y378400D01*
X105144D01*
X105233Y378311D01*
X105490D01*
X115901Y367900D01*
X120094D01*
X121878Y366116D01*
X123412D01*
X124196Y366900D01*
X138131D01*
X140018Y365013D01*
X146623D01*
X148558Y363078D01*
X167198D01*
X167317Y363197D01*
X203270D01*
X209454Y357013D01*
X219537D01*
X219580Y356970D01*
G01X74301Y538390D02*
X70707D01*
X64168Y531851D01*
X58463D01*
X58109Y531497D01*
X56218D01*
X56217Y531496D01*
X56216D01*
X39789Y515069D01*
Y487111D01*
X39790Y487110D01*
Y487109D01*
X42079Y484820D01*
Y477868D01*
X43570Y476377D01*
Y453965D01*
X53800Y443735D01*
Y443734D01*
X56718Y440816D01*
Y430201D01*
X56717Y430200D01*
Y424400D01*
X56719Y424398D01*
Y424357D01*
X57033Y424043D01*
Y422550D01*
X55950Y421467D01*
Y419779D01*
X59650Y416079D01*
X66099Y409628D01*
X67985Y407742D01*
Y407740D01*
X79090Y396635D01*
Y395222D01*
X80173Y394139D01*
X81115D01*
X83353Y391901D01*
X86247D01*
X101748Y376400D01*
X104572D01*
X115172Y365800D01*
X118701D01*
X120385Y364116D01*
X125799D01*
X126033Y364350D01*
X137852D01*
X139189Y363013D01*
X145794D01*
X147729Y361078D01*
X202317D01*
X208382Y355013D01*
X285959D01*
X294009Y363063D01*
G01X77372Y526885D02*
X75337Y524850D01*
X61364D01*
X61011Y524497D01*
X61010D01*
X61009Y524496D01*
X59117D01*
X56278Y521657D01*
Y521656D01*
X46790Y512168D01*
Y490011D01*
X52826Y483975D01*
Y481909D01*
X58943Y475791D01*
Y471709D01*
X61150Y469502D01*
Y446928D01*
X63718Y444360D01*
Y427300D01*
X63719Y427299D01*
Y427258D01*
X67043Y423934D01*
Y419792D01*
X78500Y408335D01*
X80154D01*
X84922Y403567D01*
X84923D01*
X93405Y395085D01*
X94448D01*
X95146Y395086D01*
X95530D01*
X95531Y395085D01*
X95547D01*
X104201Y386431D01*
Y386415D01*
X107304Y383312D01*
X109697D01*
X119557Y373452D01*
X138651D01*
X141997Y370106D01*
X150006D01*
X152034Y368078D01*
X163848D01*
X165673Y369903D01*
X179381D01*
G01X313100Y371038D02*
X308582D01*
X305494Y367950D01*
X286570D01*
X285500Y366880D01*
X232171D01*
X231101Y367950D01*
X210088D01*
X204389Y373649D01*
X142698D01*
X139895Y376452D01*
X122878D01*
X117797Y381533D01*
X117803Y382548D01*
Y384903D01*
X115006Y387700D01*
X110854D01*
X106210Y392344D01*
X104583D01*
X98816Y398111D01*
X98440D01*
X97492Y398110D01*
X95094D01*
X93892Y399312D01*
X83923Y409288D01*
Y411303D01*
X66730Y428496D01*
Y429730D01*
X66733Y448309D01*
X68000Y449580D01*
Y463931D01*
X66100Y465831D01*
Y472878D01*
X58485Y480494D01*
X57900Y481079D01*
Y483299D01*
X54400Y486799D01*
Y492100D01*
X51941Y494559D01*
X50140D01*
G01X313100Y374438D02*
X311700Y373038D01*
X307753D01*
X304665Y369950D01*
X285741D01*
X284671Y368880D01*
X233000D01*
X231930Y369950D01*
X210917D01*
X205218Y375649D01*
X143527D01*
X140724Y378452D01*
X123707D01*
X119802Y382357D01*
X119803Y382542D01*
Y385732D01*
X115835Y389700D01*
X111683D01*
X107039Y394344D01*
X105412D01*
X99645Y400111D01*
X98439D01*
X95924Y400110D01*
X85923Y410117D01*
Y412132D01*
X68730Y429325D01*
Y429729D01*
X68733Y447482D01*
X70000Y448752D01*
Y464760D01*
X68100Y466660D01*
Y473707D01*
X59900Y481908D01*
Y484128D01*
X56400Y487628D01*
Y488800D01*
X57345Y489745D01*
X60465D01*
X60987Y489223D01*
G01X301320Y362500D02*
X298907Y364913D01*
X292630D01*
X291107Y363390D01*
X282370D01*
X280660Y365100D01*
X231685D01*
X230335Y366450D01*
X207618D01*
X202315Y371753D01*
X164253D01*
X162078Y369578D01*
X152657D01*
X150629Y371606D01*
X142619D01*
X139273Y374952D01*
X121282D01*
X105561Y390673D01*
X103590D01*
X97676Y396587D01*
X94494D01*
X93500Y397581D01*
X86332Y404754D01*
X84372Y406715D01*
X82422Y408667D01*
X82261Y408828D01*
Y410838D01*
X65219Y427880D01*
Y444803D01*
X65218Y444982D01*
X62650Y447550D01*
Y470124D01*
X60443Y472331D01*
Y476413D01*
X56019Y480838D01*
Y482980D01*
X52071Y486928D01*
Y491436D01*
X50907Y492600D01*
X49482D01*
X48290Y493792D01*
Y511546D01*
X57778Y521034D01*
Y521035D01*
X59739Y522996D01*
X61631D01*
X61632Y522997D01*
X61633D01*
X61986Y523350D01*
X69712D01*
X70562Y522500D01*
X77700D01*
G01X118500Y504238D02*
X112920Y509818D01*
X71537D01*
X69099Y507380D01*
X61080D01*
X60150Y506450D01*
G01X561912Y390762D02*
X525960D01*
X505022Y411700D01*
X457978D01*
X436678Y390400D01*
X302302D01*
X295734Y383832D01*
X216369D01*
X211186Y378649D01*
X144771D01*
X141968Y381452D01*
X124951D01*
X122803Y383600D01*
Y386976D01*
X111643Y398136D01*
X108403D01*
X108402Y398135D01*
X106332D01*
X106294Y398173D01*
X105827D01*
X100889Y403111D01*
X97173D01*
X95729Y404553D01*
X95728Y404555D01*
X89411Y410873D01*
Y412883D01*
X88923Y413371D01*
Y413376D01*
X74775Y427524D01*
Y444639D01*
X73000Y446414D01*
Y471700D01*
X71108Y473592D01*
Y481292D01*
X64500Y487900D01*
Y490449D01*
X61849Y493100D01*
X60305D01*
X59050Y494355D01*
Y495889D01*
X65861Y502700D01*
X66541D01*
X72159Y508318D01*
X111326D01*
X115373Y504271D01*
G01X121673Y523170D02*
X80987D01*
X78467Y520650D01*
X70290D01*
X69090Y521850D01*
X62608D01*
X62255Y521497D01*
X62254D01*
X62253Y521496D01*
X60361D01*
X59278Y520413D01*
Y520412D01*
X57550Y518684D01*
Y493733D01*
X59783Y491500D01*
X61327D01*
X62900Y489927D01*
Y487200D01*
X69608Y480492D01*
Y467292D01*
X71500Y465400D01*
Y445792D01*
X73275Y444017D01*
Y426902D01*
X87423Y412754D01*
Y412749D01*
X87863Y412309D01*
Y410299D01*
X87910Y410252D01*
X94494Y403666D01*
X96551Y401611D01*
X100267D01*
X105605Y396273D01*
X111384D01*
X121303Y386354D01*
Y382978D01*
X124329Y379952D01*
X141346D01*
X144149Y377149D01*
X205840D01*
X211222Y371767D01*
X236953D01*
X238004Y370716D01*
X282428D01*
X283933Y372221D01*
X304523D01*
X310158Y377856D01*
X349361D01*
X398100Y329117D01*
Y313703D01*
X408399Y303401D01*
Y294733D01*
X408400Y283244D01*
Y219600D01*
X410900Y217100D01*
G01X61870Y515670D02*
X66222Y511318D01*
X116282D01*
X119670Y507930D01*
X127355D01*
X130985Y504300D01*
G01X61128Y519646D02*
X61282Y519800D01*
X62700D01*
X63250Y520350D01*
X68467D01*
X72167Y516650D01*
X78467D01*
X83437Y521620D01*
X122316D01*
X123866Y523170D01*
X124823D01*
G01X528850Y394750D02*
X524094D01*
X505644Y413200D01*
X442556D01*
X421256Y391900D01*
X301680D01*
X295112Y385332D01*
X215516D01*
X210333Y380149D01*
X156843D01*
X156842Y380150D01*
X155600D01*
X155599Y380151D01*
X153113D01*
X153111Y380149D01*
X145393D01*
X136863Y388679D01*
X128172D01*
X113678Y403173D01*
X107899D01*
X102961Y408111D01*
X99245D01*
X96930Y410426D01*
Y412564D01*
X83909Y425585D01*
Y431839D01*
X81139Y434608D01*
X79775Y435972D01*
Y446711D01*
X78000Y448486D01*
Y476836D01*
X66100Y488736D01*
Y491549D01*
X65850Y491799D01*
Y499887D01*
X68182Y502219D01*
X70910D01*
G01X73232Y476912D02*
X75500Y474644D01*
Y447450D01*
X77275Y445675D01*
Y433271D01*
X81409Y429137D01*
Y424549D01*
X94430Y411528D01*
Y409390D01*
X98209Y405611D01*
X101925D01*
X106900Y400636D01*
X112679D01*
X125672Y387643D01*
Y386772D01*
X125600Y386700D01*
G01X107358Y409942D02*
X106788D01*
X101051Y415679D01*
X99677D01*
X87910Y427446D01*
Y440028D01*
X83800Y444138D01*
Y444392D01*
X83799Y444393D01*
Y445795D01*
X83800Y445796D01*
Y467517D01*
X84933Y468650D01*
X88633D01*
X88733Y468550D01*
X90467D01*
X92517Y466500D01*
X97100D01*
G01X166321Y388316D02*
X160154Y382149D01*
X157672D01*
X157671Y382150D01*
X156429D01*
X156428Y382151D01*
X152284D01*
X152282Y382149D01*
X146222D01*
X137691Y390680D01*
X136035D01*
X129001Y390679D01*
X112034Y407646D01*
X106255D01*
X100222Y413679D01*
X98750D01*
X85909Y426520D01*
X85910Y433801D01*
Y438276D01*
X85042Y439144D01*
G01X98400Y454400D02*
X92481Y460319D01*
X89270D01*
X85800Y456849D01*
Y444967D01*
X89910Y440857D01*
Y428275D01*
X100506Y417679D01*
X101880D01*
X106812Y412747D01*
X107404D01*
X110505Y409646D01*
X112863D01*
X129485Y393024D01*
X146084D01*
X152605Y386503D01*
X153445D01*
X155657Y384291D01*
G01X67700Y499120D02*
X73548Y493272D01*
X89521D01*
X91030Y491763D01*
X105205D01*
X106714Y493272D01*
X126420D01*
X127971Y494823D01*
G01X131121Y513721D02*
X129571Y515271D01*
X79210D01*
X79089Y515150D01*
X71050D01*
X67700Y518500D01*
G01X67162Y515142D02*
X67658D01*
X69150Y513650D01*
X119551D01*
X121030Y512171D01*
X129520D01*
X131121Y510570D01*
G01X74300Y533600D02*
X74451Y533751D01*
X81892D01*
X82993Y532650D01*
X119123D01*
X120706Y531067D01*
X131764D01*
X133315Y532618D01*
X134272D01*
G01X69500Y586000D02*
X69700Y586200D01*
X87000D01*
X92000Y591200D01*
G01X253500Y590500D02*
X253828Y590172D01*
Y588353D01*
X252718Y587243D01*
X249991D01*
X249035Y588199D01*
Y614274D01*
X244107Y619202D01*
Y628276D01*
X200046Y672337D01*
X148385D01*
X101720Y719002D01*
Y727780D01*
X98961Y730539D01*
X96461D01*
X95400Y731600D01*
G01X257413Y590500D02*
X255828Y588915D01*
Y587524D01*
X253547Y585243D01*
X249162D01*
X247035Y587370D01*
Y613445D01*
X242107Y618373D01*
Y627447D01*
X199217Y670337D01*
X147556D01*
X99720Y718173D01*
Y726951D01*
X98132Y728539D01*
X95739D01*
X95400Y728200D01*
G01X235750Y419500D02*
X233050Y416800D01*
X227400D01*
X222350Y411750D01*
X185424D01*
X178807Y418367D01*
X146633D01*
X138900Y426100D01*
Y428400D01*
X131800Y435500D01*
Y439100D01*
X120000Y450900D01*
Y451285D01*
G01X107900Y448900D02*
X109800Y447000D01*
X117678D01*
X128000Y436678D01*
Y430727D01*
X133300Y425427D01*
Y417800D01*
X136727Y414373D01*
X178531D01*
X182675Y410229D01*
X222951D01*
X228022Y415300D01*
X234167D01*
X238767Y419900D01*
X248661D01*
X250311Y418250D01*
X250449D01*
X250800Y417899D01*
X312357D01*
X312857Y417399D01*
X316899D01*
X337591Y438091D01*
X536509D01*
X560900Y413700D01*
G01X136500Y417400D02*
X134800Y419100D01*
Y426049D01*
X129500Y431349D01*
Y437300D01*
X118000Y448800D01*
X111200D01*
X109000Y451000D01*
Y455500D01*
X106800Y457700D01*
Y463800D01*
X101200Y469400D01*
Y470400D01*
G01X129520Y448660D02*
X129630D01*
X131529Y450559D01*
X131780D01*
X135150Y453929D01*
Y458350D01*
X135871Y459071D01*
Y490124D01*
X137421Y491674D01*
G01X123696Y454452D02*
X126373Y457129D01*
Y476813D01*
X129570Y480010D01*
Y493272D01*
X131121Y494823D01*
G01X107000Y717800D02*
X142250Y682550D01*
X210800D01*
X221650Y671700D01*
X312600D01*
X320000Y679100D01*
Y718200D01*
G01X205915Y422424D02*
X205413Y422926D01*
X204236D01*
X202006Y425156D01*
X147644D01*
X138514Y434286D01*
X137883D01*
X137000Y435169D01*
Y436700D01*
G01Y451300D02*
X135150Y449450D01*
Y434897D01*
X146747Y423300D01*
X177678D01*
X187728Y413250D01*
X219750D01*
X226300Y419800D01*
X233433D01*
X234983Y421350D01*
X238095D01*
X238145Y421400D01*
X249421D01*
X249850Y420971D01*
Y420833D01*
X250933Y419750D01*
X315572D01*
X335413Y439591D01*
X543309D01*
X567150Y415750D01*
G01X145901Y441262D02*
X148015Y443376D01*
Y445643D01*
X147988Y445670D01*
Y452534D01*
X151570Y456116D01*
Y490124D01*
X150020Y491674D01*
G01X313500Y437400D02*
X312200D01*
X308732Y433932D01*
X204277D01*
X204276Y433933D01*
X203034D01*
X203033Y433934D01*
X201791D01*
X197513Y429656D01*
X152422D01*
X142383Y439695D01*
Y446521D01*
X144112Y448250D01*
Y477411D01*
X143547Y477976D01*
G01X313300Y429603D02*
X311971Y430932D01*
X203033D01*
X198757Y426656D01*
X149644D01*
X139383Y436917D01*
Y436934D01*
X137169Y439148D01*
Y443945D01*
X139194Y445970D01*
Y447972D01*
X140445Y449223D01*
Y483055D01*
X142121Y484731D01*
Y486924D01*
X143721Y488524D01*
G01Y485374D02*
X143021Y484674D01*
Y484221D01*
X141345Y482545D01*
Y469222D01*
X142612Y467955D01*
Y448872D01*
X140883Y447143D01*
Y438000D01*
X150727Y428156D01*
X198135D01*
X202412Y432433D01*
X203654D01*
X203655Y432432D01*
X311132D01*
X312700Y434000D01*
X313288D01*
X313294Y434006D01*
G01X153100Y439000D02*
Y445683D01*
X154719Y447302D01*
Y490125D01*
X153170Y491674D01*
G01X150020Y488524D02*
Y487848D01*
X148426Y486254D01*
Y458562D01*
X145612Y455748D01*
Y447628D01*
X143883Y445899D01*
Y440317D01*
X144800Y439400D01*
X149180D01*
X152978Y435602D01*
G01X137344Y446737D02*
X137345Y446738D01*
Y448245D01*
X138945Y449845D01*
Y468622D01*
X139000Y468677D01*
Y490103D01*
X140571Y491674D01*
G01X163440Y453020D02*
X162618Y453842D01*
Y485374D01*
G01X293800Y436100D02*
X293132Y435432D01*
X204899D01*
X204898Y435433D01*
X203656D01*
X203655Y435434D01*
X201169D01*
X197885Y432150D01*
X182588D01*
X164684Y450054D01*
Y451776D01*
X163440Y453020D01*
G01X156319Y491674D02*
X157869Y490124D01*
Y483509D01*
X157232Y482872D01*
Y451086D01*
X159239Y449079D01*
G01X159082Y452509D02*
X161019Y454446D01*
Y490124D01*
X159469Y491674D01*
G01X313500Y441000D02*
X310450Y437950D01*
X266267D01*
X263667Y440550D01*
X260112D01*
X256494Y436932D01*
X216398D01*
X212767Y440563D01*
X197000D01*
X168499Y469064D01*
Y491136D01*
X163262Y496373D01*
X146226D01*
X143721Y493868D01*
Y491674D01*
G01X323600Y717800D02*
Y694200D01*
X321500Y692100D01*
Y678478D01*
X313222Y670200D01*
X221028D01*
X210178Y681050D01*
X165350D01*
X162100Y677800D01*
G01X167600Y247600D02*
X179353Y235847D01*
X269798D01*
X270464Y235181D01*
X271998D01*
X272664Y235847D01*
X286747D01*
X302500Y251600D01*
G01X315900Y320900D02*
X313390Y323410D01*
X302739D01*
X299369Y320040D01*
X282931D01*
X279062Y323909D01*
X215425D01*
X212103Y327231D01*
X202863D01*
X195839Y320207D01*
X192462D01*
X192407Y320262D01*
G01X180571Y327023D02*
X181140Y326454D01*
X199257D01*
X202034Y329231D01*
X212932D01*
X216254Y325909D01*
X253709D01*
X260470Y332670D01*
X273130D01*
X283700Y322100D01*
G01X226300Y505700D02*
X243854D01*
X248758Y510604D01*
X262608D01*
X265582Y507630D01*
Y503579D01*
X270175Y498986D01*
Y487681D01*
X274856Y483000D01*
X286900D01*
X297600Y472300D01*
X308600D01*
X312800Y468100D01*
Y461100D01*
X319700Y454200D01*
Y426000D01*
X316850Y423150D01*
X270750D01*
X266468Y427432D01*
X226233D01*
X216605Y417804D01*
X205089D01*
X203638Y419255D01*
X194400D01*
X194045Y418900D01*
Y417913D01*
X195349Y416609D01*
X200100Y415100D01*
G01X226530Y502307D02*
X227679D01*
X228999Y503627D01*
X229964D01*
X230037Y503700D01*
X244683D01*
X249587Y508604D01*
X261779D01*
X263582Y506801D01*
Y502750D01*
X268175Y498157D01*
Y486852D01*
X274027Y481000D01*
X286071D01*
X296771Y470300D01*
X307771D01*
X310800Y467271D01*
Y460271D01*
X317700Y453371D01*
Y426829D01*
X316021Y425150D01*
X271579D01*
X267297Y429432D01*
X225404D01*
X215776Y419804D01*
X205918D01*
X204467Y421255D01*
X193571D01*
X191900Y419584D01*
Y418757D01*
X191807Y418462D01*
Y418456D01*
X191750Y418285D01*
X191747Y418282D01*
X190095D01*
X185000Y419900D01*
G01X257493Y456679D02*
X254173Y459999D01*
X254170Y460000D01*
X227197D01*
X224897Y457700D01*
X213078D01*
X209278Y461500D01*
X204800D01*
X197600Y468700D01*
X188714D01*
X181514Y475900D01*
Y479075D01*
G01X253302Y456679D02*
X251981Y458000D01*
X228026D01*
X225726Y455700D01*
X212249D01*
X208449Y459500D01*
X203971D01*
X196771Y466700D01*
X187885D01*
X179514Y475071D01*
Y478175D01*
X176767Y480922D01*
Y486015D01*
X175858Y486924D01*
X174622D01*
X173666Y487880D01*
Y489116D01*
X172065Y490717D01*
Y491674D01*
G01X257400Y477300D02*
Y477737D01*
X256637Y478500D01*
X255000D01*
X253700Y477200D01*
Y475334D01*
X239966Y461600D01*
X226675D01*
X224275Y459200D01*
X213700D01*
X187478Y485422D01*
X186586D01*
X186455Y485291D01*
X184799D01*
X184717Y485373D01*
X184665D01*
X184664Y485372D01*
G01X257400Y481637D02*
Y481262D01*
X256638Y480500D01*
X254171D01*
X251700Y478029D01*
Y476163D01*
X239137Y463600D01*
X225846D01*
X223446Y461200D01*
X214529D01*
X188307Y487422D01*
X185757D01*
X185307Y486972D01*
X184021D01*
X183089Y487904D01*
Y489142D01*
X182132Y490099D01*
X174597D01*
X173640Y491056D01*
Y493248D01*
X172065Y494823D01*
G01Y510571D02*
X173022D01*
X174572Y512121D01*
X175808D01*
X176800Y513113D01*
Y520648D01*
X177722Y521570D01*
X216653D01*
X216733Y521650D01*
X218267D01*
X218836Y521081D01*
X239321D01*
G01X244100Y499900D02*
X242373Y501627D01*
X229828D01*
X228101Y499900D01*
X218746D01*
X218246Y500400D01*
X214954D01*
X214454Y499900D01*
X209400D01*
X207950Y501350D01*
X201700D01*
X196773Y496423D01*
X174572D01*
X173665Y497330D01*
Y498566D01*
X172065Y500166D01*
Y501122D01*
G01X256300Y486000D02*
X255133Y487167D01*
X251729D01*
X250150Y485588D01*
Y477004D01*
X238646Y465500D01*
X212800D01*
X187076Y491224D01*
X185498D01*
X184664Y490390D01*
Y488522D01*
G01X256300Y490000D02*
X255467Y489167D01*
X250900D01*
X248150Y486417D01*
Y477833D01*
X237817Y467500D01*
X213629D01*
X187905Y493224D01*
X176814D01*
X175215Y494823D01*
G01X172065Y504272D02*
X173022D01*
X174573Y502721D01*
X175859D01*
X176766Y503628D01*
Y504866D01*
X177772Y505872D01*
X188299D01*
X194927Y512500D01*
X215183D01*
X217033Y510650D01*
X218567D01*
X219017Y511100D01*
X223601D01*
X225182Y512681D01*
X239243D01*
X244118Y517556D01*
X265804D01*
X284331Y499029D01*
Y497779D01*
X285414Y496696D01*
X289248D01*
X297372Y488572D01*
X303095D01*
X317200Y474467D01*
Y471659D01*
X322268Y466591D01*
G01X322305Y469991D02*
Y474812D01*
X293068Y504049D01*
X281726D01*
X266719Y519056D01*
X230173D01*
X225517Y514400D01*
X192199D01*
X186820Y509021D01*
X174621D01*
X173665Y508065D01*
Y505822D01*
X175216Y504271D01*
G01X172065Y507422D02*
Y507365D01*
X170515Y505815D01*
Y503629D01*
X171422Y502722D01*
X172658D01*
X173665Y501715D01*
Y500479D01*
X174572Y499572D01*
X191100D01*
X200328Y508800D01*
X214300D01*
X218800Y504300D01*
X222283D01*
X227662Y509679D01*
X240485D01*
X245362Y514556D01*
X264560D01*
X267082Y512034D01*
Y508633D01*
X267083Y508632D01*
Y505732D01*
X267082Y505731D01*
Y504263D01*
X277845Y493500D01*
X288200D01*
X300350Y481350D01*
X301672D01*
X314300Y468722D01*
Y467400D01*
X321900Y459800D01*
G01X322036Y463198D02*
X298673Y486561D01*
X297261D01*
X288626Y495196D01*
X281865D01*
X268583Y508478D01*
Y509254D01*
X268582Y512656D01*
X265182Y516056D01*
X244740D01*
X239864Y511180D01*
X227041D01*
X222161Y506300D01*
X219000D01*
X215000Y510300D01*
X198000D01*
X192672Y504972D01*
X179065D01*
X178365Y504272D01*
G01X172065Y513721D02*
X173666Y515322D01*
Y522526D01*
X173665Y522527D01*
Y523813D01*
X174572Y524720D01*
X230640D01*
X230997Y525077D01*
X239139D01*
G01X172065Y535768D02*
X173615Y537318D01*
X182318D01*
X196150Y551150D01*
X209122D01*
X211122Y553150D01*
X217050D01*
X219700Y550500D01*
G01X165766Y542066D02*
X181926Y558226D01*
X198146D01*
X201533Y561613D01*
X206467D01*
X207605Y560475D01*
X217525D01*
X217918Y560082D01*
X218780D01*
G01X303800Y505100D02*
X293500Y515400D01*
X277300D01*
X268813Y523887D01*
X248933D01*
X245220Y527600D01*
X219645D01*
X219445Y527400D01*
X216733D01*
X216233Y527900D01*
X173646D01*
X172065Y526319D01*
G01X178365Y529469D02*
X182669D01*
X184300Y531100D01*
X218267D01*
X220267Y529100D01*
X265722D01*
X277922Y516900D01*
X298900D01*
X304400Y511400D01*
G01X172065Y529469D02*
X172169D01*
X173768Y531068D01*
X182995D01*
X184527Y532600D01*
X218889D01*
X220889Y530600D01*
X266344D01*
X278544Y518400D01*
X300017D01*
X306250Y512167D01*
Y505267D01*
X329014Y482503D01*
Y472022D01*
G01X279994Y554794D02*
X269843Y564945D01*
X208921D01*
X207089Y563113D01*
X200742D01*
X198675Y561046D01*
X191632D01*
X189500Y563178D01*
Y567700D01*
G01X193001Y574708D02*
X194489Y573220D01*
X222500D01*
G01X296200Y566900D02*
X279404D01*
X270454Y575850D01*
X262950D01*
X257800Y581000D01*
X244500D01*
X233500Y592000D01*
X200089D01*
X199989Y592100D01*
X188178D01*
X186778Y590700D01*
X186700D01*
X181000Y585000D01*
G01X327512Y509612D02*
X319274Y517850D01*
X314731D01*
X313648Y518933D01*
X303117Y529465D01*
X299900Y532682D01*
Y560900D01*
X295750Y565050D01*
X295433D01*
X295083Y565400D01*
X278782D01*
X269832Y574350D01*
X262328D01*
X257179Y579499D01*
X243879D01*
X232878Y590500D01*
X214000D01*
X205000Y581500D01*
X181000D01*
G01X279257Y226340D02*
X280440Y225157D01*
Y206160D01*
X317200Y169400D01*
Y134600D01*
X309150Y126550D01*
X253350D01*
X243174Y116374D01*
Y109946D01*
X236234Y103006D01*
X222354D01*
G01X257912Y101408D02*
X256546Y100042D01*
X250114D01*
X248450Y98378D01*
X227870D01*
X227606Y98642D01*
G01X258029Y97353D02*
X257471D01*
X256782Y98042D01*
X250943D01*
X249279Y96378D01*
X225551D01*
X223641Y98288D01*
Y99302D01*
G01X267300Y362200D02*
X267100Y362000D01*
X232400D01*
X230500Y363900D01*
X228800D01*
X228100Y364600D01*
G01X219018Y378000D02*
X220474Y376544D01*
Y375566D01*
X222273Y373767D01*
X238611D01*
X239662Y372716D01*
X281599D01*
X283104Y374221D01*
X303694D01*
X309329Y379856D01*
X310036D01*
X310080Y379900D01*
X432771D01*
X435535Y377135D01*
Y377136D01*
X463371Y349300D01*
X477201D01*
X479300Y351399D01*
Y355100D01*
X480000Y355800D01*
G01X223383Y378000D02*
X222474Y377090D01*
Y376395D01*
X223102Y375767D01*
X239440D01*
X240491Y374716D01*
X280770D01*
X282275Y376221D01*
X302865D01*
X308500Y381856D01*
X309207D01*
X309251Y381900D01*
X433600D01*
X464200Y351300D01*
X476372D01*
X477300Y352228D01*
Y355100D01*
X476600Y355800D01*
G01X283400Y477900D02*
X282299Y479000D01*
X270242D01*
X257392Y491850D01*
X250250D01*
X249800Y491400D01*
X246100D01*
X234400Y479700D01*
X220866D01*
X220502Y479336D01*
X208817D01*
X208653Y479500D01*
X205955D01*
X201700Y483755D01*
Y487400D01*
X203350Y489050D01*
Y492900D01*
X202700Y493550D01*
Y495400D01*
G01X246800Y496800D02*
X246050Y497550D01*
X239633D01*
X239483Y497700D01*
X239100D01*
X238673Y498127D01*
X231279D01*
X229452Y496300D01*
X224794D01*
X224294Y495800D01*
X219300D01*
X219050Y495550D01*
X219033D01*
X217950Y494467D01*
Y494450D01*
X217400Y493900D01*
X211800D01*
X208041Y497659D01*
X207041D01*
X206700Y498000D01*
G01X242800Y495486D02*
X239276D01*
X238562Y496200D01*
X238478D01*
X238051Y496627D01*
X231901D01*
X230074Y494800D01*
X225500D01*
X222500Y491800D01*
X211750D01*
X207700Y495850D01*
X205850D01*
X204212Y497488D01*
X201916D01*
X200400Y495972D01*
Y493100D01*
X200917Y492583D01*
Y490578D01*
G01X203550Y484522D02*
X204328Y485300D01*
X205753D01*
X206259Y485806D01*
X207793D01*
X208299Y485300D01*
X222000D01*
X228500Y491800D01*
X231813D01*
X233290Y493277D01*
G01X206700Y494000D02*
Y490400D01*
X210100Y487000D01*
X221477D01*
X227777Y493300D01*
X230696D01*
X232523Y495127D01*
X237429D01*
X237856Y494700D01*
X237940D01*
X239240Y493400D01*
X246500D01*
G01X240450Y499400D02*
X240400D01*
X240173Y499627D01*
X230657D01*
X228830Y497800D01*
X218017D01*
X217417Y498400D01*
X215783D01*
X215183Y497800D01*
X209600D01*
X207750Y499650D01*
X205733D01*
X205183Y499100D01*
X203600D01*
X203500Y499200D01*
G01X207026Y483956D02*
X209646Y481336D01*
X219673D01*
X220037Y481700D01*
X231500D01*
X234733Y484933D01*
Y491166D01*
X236737Y493170D01*
G01X295876Y520800D02*
X283076Y533600D01*
X222133D01*
X220133Y535600D01*
X206200D01*
X203300Y538500D01*
G01X327589Y504300D02*
X317039Y514850D01*
X313450D01*
X283250Y545050D01*
X219589D01*
X219039Y544500D01*
X206700D01*
G01X335570Y491460D02*
X313680Y513350D01*
X312139D01*
X282339Y543150D01*
X219811D01*
X219311Y542650D01*
X202533D01*
X200683Y544500D01*
X199900D01*
G01X333102Y485902D02*
Y486191D01*
X307750Y511543D01*
Y512789D01*
X285439Y535100D01*
X222755D01*
X220755Y537100D01*
X208100D01*
X206700Y538500D01*
G01X330000Y501900D02*
Y504506D01*
X318156Y516350D01*
X314109D01*
X282409Y548050D01*
X260333D01*
X259883Y548500D01*
X206700D01*
G01X202300Y559763D02*
X204305Y557758D01*
X217625D01*
X221309Y554074D01*
X273926D01*
X278450Y549550D01*
X281750D01*
X283600Y551400D01*
G01X280200D02*
X273100Y558500D01*
X229800D01*
G01X283622Y226340D02*
X282440Y225158D01*
Y206989D01*
X319200Y170229D01*
Y133771D01*
X309979Y124550D01*
X254179D01*
X245400Y115771D01*
Y111853D01*
X251903Y105350D01*
X264817D01*
G01X284440Y139580D02*
X283560Y138700D01*
X281918D01*
X279468Y136250D01*
X234250D01*
X233500Y137000D01*
G01X539400Y376444D02*
X537944Y377900D01*
X533871D01*
X503571Y408200D01*
X459429D01*
X438129Y386900D01*
X306518D01*
X298417Y378799D01*
X245182D01*
X244000Y377617D01*
G01X539400Y380781D02*
X538519Y379900D01*
X534700D01*
X504400Y410200D01*
X458600D01*
X437300Y388900D01*
X305689D01*
X297588Y380799D01*
X245183D01*
X244000Y381982D01*
G01X251800Y470100D02*
X252296Y467782D01*
X255378Y464700D01*
X278929D01*
X285629Y458000D01*
X293371D01*
X297221Y461850D01*
X300240D01*
X301170Y462780D01*
G01X248500Y465000D02*
X250039Y465330D01*
X251736D01*
X251737Y465331D01*
X251918D01*
X254549Y462700D01*
X278100D01*
X284800Y456000D01*
X294200D01*
X298050Y459850D01*
X300602D01*
X301162Y459290D01*
G01X263700Y474600D02*
X265600Y476500D01*
X267851D01*
X268369Y475982D01*
Y473394D01*
X270558Y471205D01*
X288566D01*
X295141Y464630D01*
X301937D01*
X302421Y464146D01*
X303454D01*
X304024Y463576D01*
X306521D01*
G01X253500Y590500D02*
X254290Y591290D01*
Y597719D01*
X257871Y601300D01*
X300917D01*
X308200Y594017D01*
Y547773D01*
X308908Y547065D01*
X310565D01*
X311500Y548000D01*
G01X257413Y590500D02*
X256290Y591623D01*
Y596890D01*
X258700Y599300D01*
X300088D01*
X306200Y593188D01*
Y546944D01*
X308079Y545065D01*
X312045D01*
X313216Y546236D01*
Y546316D01*
X314900Y548000D01*
G01X262628Y744470D02*
X263358Y745200D01*
X293692D01*
X294058Y744834D01*
X319966D01*
X332200Y732600D01*
Y684000D01*
X581000Y435200D01*
X597200D01*
X604400Y428000D01*
Y421200D01*
G01X729132Y3575D02*
X726613D01*
X725407Y2369D01*
X701872D01*
X701871Y2368D01*
X700629D01*
X696583Y6414D01*
X519655D01*
X490904Y35149D01*
X477038D01*
X376985Y135202D01*
Y190605D01*
X386995Y200615D01*
Y295096D01*
X379763Y302328D01*
X379344Y302748D01*
X378049Y304044D01*
X378048Y304045D01*
Y304049D01*
X377100Y305001D01*
Y314734D01*
X367436Y324398D01*
X367063D01*
X367062Y324399D01*
X364576D01*
X364575Y324398D01*
X345731D01*
X334128Y336001D01*
X297371D01*
X288172Y326802D01*
X287200D01*
G01X919486Y5908D02*
X916083Y2505D01*
X897400D01*
X895755Y4150D01*
X878963D01*
X868766Y-6047D01*
X810224D01*
X810221Y-6045D01*
X796473Y7700D01*
X778172D01*
X774281Y3809D01*
X742980D01*
X740040Y869D01*
X702494D01*
X702493Y868D01*
X700007D01*
X695961Y4914D01*
X519033D01*
X490282Y33649D01*
X476416D01*
X375485Y134580D01*
Y191227D01*
X385495Y201237D01*
Y294474D01*
X378701Y301267D01*
X378282Y301687D01*
X376987Y302983D01*
X376548Y303423D01*
Y303429D01*
X375600Y304381D01*
Y314112D01*
X366814Y322898D01*
X345109D01*
X333506Y334501D01*
X301982D01*
X295400Y327919D01*
Y325390D01*
G01X273783Y476100D02*
X270961D01*
X270369Y475508D01*
Y474223D01*
X271387Y473205D01*
X289395D01*
X295970Y466630D01*
X302766D01*
X303250Y466146D01*
X304293D01*
G01X302500Y207200D02*
Y243500D01*
X306900Y247900D01*
Y251000D01*
G01X790150Y-1400D02*
Y-2933D01*
X790258Y-3041D01*
Y-5088D01*
X782911Y-12435D01*
X508051D01*
X475458Y20158D01*
X471850D01*
X352950Y139058D01*
Y186450D01*
X356200Y189700D01*
Y238500D01*
X332760Y261940D01*
Y284782D01*
X314439Y303103D01*
X307574D01*
X301667Y309010D01*
Y310544D01*
X305793Y314670D01*
X310485D01*
G01X311882Y310550D02*
X313852D01*
X316799Y307603D01*
X321743D01*
X326946Y302400D01*
X330480D01*
X332350Y300529D01*
Y298833D01*
X333433Y297750D01*
X335129D01*
X338870Y294010D01*
X338999D01*
X340960Y292049D01*
Y291920D01*
X374300Y258580D01*
Y207031D01*
X374301Y207030D01*
Y205788D01*
X367485Y198972D01*
Y130889D01*
X473715Y24659D01*
X477323D01*
X509917Y-7935D01*
X726993D01*
X727613Y-7315D01*
X728395D01*
G01X746329Y-7789D02*
X744683Y-9435D01*
X509295D01*
X476701Y23159D01*
X473093D01*
X365985Y130267D01*
Y199594D01*
X372800Y206409D01*
Y252617D01*
X319314Y306103D01*
X311160D01*
X307425Y309838D01*
G01X788408Y-4321D02*
X781794Y-10935D01*
X508673D01*
X476079Y21659D01*
X472471D01*
X364485Y129645D01*
Y234115D01*
X334260Y264340D01*
Y285404D01*
X315061Y304603D01*
X308691D01*
X303517Y309777D01*
G01X713461Y-3006D02*
X712784Y-3683D01*
X521974D01*
X488624Y29648D01*
X474384D01*
X371485Y132547D01*
Y197314D01*
X379100Y204929D01*
Y278177D01*
X341377Y315900D01*
X328800D01*
G01X362500Y341700D02*
X385600Y318600D01*
Y308520D01*
X395899Y298217D01*
Y293483D01*
X395900Y281994D01*
Y197496D01*
X385485Y187081D01*
Y138872D01*
X452114Y72243D01*
X462874D01*
X472050Y63067D01*
Y62033D01*
X479216Y54867D01*
X486053D01*
X524522Y16416D01*
X524524Y16414D01*
X533643D01*
X533644Y16415D01*
X714777D01*
X716043Y15149D01*
X729774D01*
X729775Y15148D01*
X741779D01*
X746393Y19761D01*
X748933Y22300D01*
X772870D01*
X774571Y24000D01*
X805417D01*
X826617Y2800D01*
X858550D01*
X861000Y350D01*
G01X362825Y336000D02*
X367525Y331300D01*
X370071D01*
X383600Y317771D01*
Y307691D01*
X393899Y297388D01*
Y293482D01*
X393900Y281993D01*
Y198325D01*
X383485Y187910D01*
Y138043D01*
X451285Y70243D01*
X460674D01*
X468350Y62567D01*
Y61533D01*
X477016Y52867D01*
X485224D01*
X523695Y14414D01*
X713949D01*
X715214Y13149D01*
X728945D01*
X728946Y13148D01*
X742608D01*
X742610Y13149D01*
X744228D01*
X750829Y19750D01*
X773150D01*
X775400Y22000D01*
X804421D01*
X810707Y15714D01*
Y10693D01*
X820600Y800D01*
X856956D01*
X857453Y303D01*
G01X943111Y13778D02*
X936334Y20555D01*
X919083D01*
X918110Y21528D01*
X890971D01*
X881493Y12050D01*
X821751D01*
X807400Y26401D01*
X761133D01*
X760432Y25700D01*
X755500D01*
X755495Y25695D01*
X749499D01*
X744978Y21176D01*
X740950Y17148D01*
X730604D01*
X730603Y17149D01*
X716872D01*
X715606Y18415D01*
X532815D01*
X532814Y18414D01*
X525353D01*
X525351Y18416D01*
X486882Y56867D01*
X483246D01*
X480491Y59622D01*
Y62826D01*
X469074Y74243D01*
X452943D01*
X387485Y139701D01*
Y186252D01*
X397900Y196667D01*
Y281995D01*
X397899Y293484D01*
Y299046D01*
X387600Y309349D01*
Y320388D01*
X356953Y351036D01*
Y353653D01*
G01X359403Y351203D02*
X360024D01*
X389100Y322127D01*
Y309971D01*
X399399Y299668D01*
Y293485D01*
X399400Y281996D01*
Y196045D01*
X388985Y185630D01*
Y140323D01*
X453565Y75743D01*
X470127D01*
X525970Y19919D01*
X525975Y19914D01*
X532192D01*
X532193Y19915D01*
X716228D01*
X717494Y18649D01*
X731226D01*
X732469Y18648D01*
X740327D01*
X748878Y27196D01*
X754646D01*
X754650Y27200D01*
X759810D01*
X763810Y31200D01*
X804906D01*
X822556Y13550D01*
X880871D01*
X890349Y23028D01*
X918732D01*
X919705Y22055D01*
X939431D01*
X946361Y15125D01*
Y9158D01*
X943111Y5908D01*
G01X935236Y13778D02*
X931459Y17555D01*
X917839D01*
X916866Y18528D01*
X893028D01*
X883000Y8500D01*
X879069D01*
X867522Y-3047D01*
X815377D01*
X801630Y10700D01*
X763717D01*
X759826Y6809D01*
X741736D01*
X739227Y4300D01*
X736500D01*
X733150Y7650D01*
X713640D01*
X712686Y8604D01*
X711152D01*
X709872Y7324D01*
X701161D01*
X701160Y7323D01*
X699918D01*
X697827Y9414D01*
X520899D01*
X492148Y38149D01*
X478428D01*
X379985Y136592D01*
Y189361D01*
X390400Y199776D01*
Y281991D01*
X390399Y293480D01*
Y295937D01*
X381887Y304450D01*
X381049Y305289D01*
X380100Y306241D01*
Y315978D01*
X368678Y327400D01*
X366474D01*
X352003Y341871D01*
Y358603D01*
G01X935236Y5908D02*
X938486Y9158D01*
Y15125D01*
X934556Y19055D01*
X918461D01*
X917488Y20028D01*
X891593D01*
X881565Y10000D01*
X878447D01*
X866900Y-1547D01*
X815999D01*
X799700Y14752D01*
Y18201D01*
X797901Y20000D01*
X782700D01*
X775000Y12300D01*
X758372D01*
X755222Y9150D01*
X746867D01*
X746027Y8310D01*
X741115D01*
X738605Y5800D01*
X737700D01*
X734350Y9150D01*
X714262D01*
X713308Y10104D01*
X710530D01*
X709250Y8824D01*
X700539D01*
X698449Y10914D01*
X521521D01*
X492770Y39649D01*
X480588D01*
X459550Y60687D01*
Y63067D01*
X454374Y68243D01*
X450456D01*
X381485Y137214D01*
Y188739D01*
X391900Y199154D01*
Y281992D01*
X391899Y293481D01*
Y296559D01*
X386167Y302293D01*
X382550Y305911D01*
X381600Y306862D01*
Y316600D01*
X369299Y328901D01*
X368057D01*
X368056Y328900D01*
X367096D01*
X354505Y341491D01*
Y356102D01*
G01X958856Y13778D02*
X946079Y26555D01*
X921571D01*
X920598Y27528D01*
X888483D01*
X881205Y20250D01*
X875542D01*
X875027Y20765D01*
X869833D01*
X867118Y18050D01*
X854385D01*
X852402Y20033D01*
Y20174D01*
X849818Y22758D01*
X822826D01*
X822644Y22940D01*
X819532D01*
X806772Y35700D01*
X761944D01*
X757944Y31700D01*
X751992D01*
X751991Y31699D01*
X747014D01*
X742051Y26737D01*
X702785D01*
X700463Y24415D01*
X528070D01*
X528052Y24433D01*
X472224Y80244D01*
X468261D01*
X468260Y80243D01*
X455431D01*
X393485Y142189D01*
Y176729D01*
X403900Y187144D01*
Y282620D01*
X403899Y294109D01*
Y301534D01*
X393600Y311837D01*
Y323993D01*
X360820Y356773D01*
Y359299D01*
G01X363270Y356940D02*
X363528D01*
X395100Y325368D01*
Y312459D01*
X405399Y302156D01*
Y294110D01*
X405400Y283242D01*
Y186522D01*
X394985Y176107D01*
Y142811D01*
X456053Y81743D01*
X467638D01*
X467639Y81744D01*
X472846D01*
X473111Y81479D01*
X473113Y81478D01*
X528691Y25916D01*
X528692Y25915D01*
X699841D01*
X702163Y28237D01*
X741429D01*
X746393Y33200D01*
X757322D01*
X761457Y37335D01*
X807259D01*
X816974Y27620D01*
X850049D01*
X856102Y21567D01*
Y20781D01*
X857333Y19550D01*
X866496D01*
X869211Y22265D01*
X875649D01*
X876164Y21750D01*
X880583D01*
X887861Y29028D01*
X921220D01*
X922193Y28055D01*
X949176D01*
X962106Y15125D01*
Y9158D01*
X958856Y5908D01*
G01X950986Y13778D02*
X941209Y23555D01*
X920327D01*
X919354Y24528D01*
X889727D01*
X880249Y15050D01*
X823178D01*
X805528Y32700D01*
X763188D01*
X759188Y28700D01*
X753724D01*
X753721Y28697D01*
X748256D01*
X743295Y23737D01*
X735436D01*
X731848Y20149D01*
X718116D01*
X716850Y21415D01*
X531571D01*
X531570Y21414D01*
X526827D01*
X526825Y21416D01*
X470979Y77243D01*
X454187D01*
X390485Y140945D01*
Y185008D01*
X400900Y195423D01*
Y282618D01*
X400899Y293486D01*
Y300290D01*
X390600Y310593D01*
Y322749D01*
X355872Y357477D01*
Y363965D01*
G01X950986Y5908D02*
X954236Y9158D01*
Y15125D01*
X944306Y25055D01*
X920949D01*
X919976Y26028D01*
X889105D01*
X879627Y16550D01*
X823800D01*
X806150Y34200D01*
X762566D01*
X758566Y30200D01*
X752919D01*
X752917Y30198D01*
X747635D01*
X742673Y25237D01*
X732937D01*
X730601Y22901D01*
X720723D01*
X719775Y23849D01*
X702019D01*
X701085Y22915D01*
X527448D01*
X527429Y22934D01*
X471601Y78744D01*
X468882D01*
X468880Y78743D01*
X454809D01*
X391985Y141567D01*
Y184386D01*
X402400Y194801D01*
Y282619D01*
X402399Y294108D01*
Y300912D01*
X392100Y311215D01*
Y323371D01*
X358362Y357109D01*
Y361649D01*
G01X334800Y712000D02*
Y685500D01*
X582400Y437900D01*
X599600D01*
X615500Y422000D01*
Y420100D01*
G01X354300Y696000D02*
Y704500D01*
G01X883800Y-500D02*
Y-2666D01*
X876419Y-10047D01*
X808562D01*
X795665Y2850D01*
X784750D01*
X781708Y-192D01*
X744637D01*
X739514Y-5315D01*
X726325D01*
X725705Y-5935D01*
X510746D01*
X478152Y26659D01*
X474544D01*
X369485Y131718D01*
Y198143D01*
X376600Y205258D01*
Y261350D01*
G01X381700Y265800D02*
Y204700D01*
X373485Y196485D01*
Y133751D01*
X475587Y31649D01*
X489452D01*
X518204Y2914D01*
X695132D01*
X699178Y-1132D01*
X703322D01*
X703323Y-1131D01*
X740869D01*
X743809Y1809D01*
X745465D01*
X745466Y1808D01*
X775109D01*
X779001Y5700D01*
X795644D01*
X809392Y-8046D01*
X809395Y-8047D01*
X871353D01*
X881700Y2300D01*
G01X863300Y23575D02*
X859256D01*
X853711Y29120D01*
X817596D01*
X807881Y38835D01*
X760835D01*
X756700Y34700D01*
X745770D01*
X740807Y29737D01*
X701541D01*
X699219Y27415D01*
X534973D01*
X531862Y27416D01*
X529313D01*
X474002Y82712D01*
X473470Y83244D01*
X467017D01*
X467016Y83243D01*
X456675D01*
X396485Y143433D01*
Y175485D01*
X406900Y185900D01*
Y283243D01*
X406899Y294732D01*
Y302778D01*
X396600Y313081D01*
Y328000D01*
X370700Y353900D01*
G01X480368Y405606D02*
X479550Y404788D01*
Y385950D01*
X490800Y374700D01*
Y354909D01*
X419611Y283720D01*
Y187689D01*
X433300Y174000D01*
X435386D01*
X437911Y171475D01*
Y167542D01*
X438561Y166892D01*
G01X435161D02*
X435911Y167642D01*
Y170646D01*
X434557Y172000D01*
X432471D01*
X417611Y186860D01*
Y284549D01*
X488800Y355738D01*
Y373871D01*
X477550Y385121D01*
Y404587D01*
X476531Y405606D01*
G01X422876Y199830D02*
X424022Y200976D01*
X429758D01*
X436883Y208101D01*
Y283055D01*
X476284Y322456D01*
Y333088D01*
X477037Y333841D01*
G01X422876Y204195D02*
Y204191D01*
X424091Y202976D01*
X428929D01*
X434883Y208930D01*
Y283884D01*
X474284Y323285D01*
Y333229D01*
X473637Y333876D01*
G01X762300Y16200D02*
X760150D01*
X755099Y11149D01*
X743438D01*
X743437Y11148D01*
X728117D01*
X728116Y11149D01*
X716043D01*
X716042Y11148D01*
X714386D01*
X713930Y11604D01*
X709804D01*
X708524Y10324D01*
X701776D01*
X699686Y12414D01*
X522144D01*
X522142Y12415D01*
X522126Y12431D01*
X493392Y41149D01*
X481705D01*
X465127Y57727D01*
G01X697494Y186256D02*
X696325Y185087D01*
X693413D01*
X682860Y195640D01*
X623760D01*
X617931Y189811D01*
X604718D01*
X603767Y188860D01*
X602233D01*
X601282Y189811D01*
X560604D01*
X548244Y177451D01*
X512305D01*
X503154Y168300D01*
X485188D01*
X480645Y172843D01*
X468822D01*
X464279Y168300D01*
X457983D01*
X456500Y169783D01*
G01X697494Y181919D02*
X696326Y183087D01*
X692584D01*
X682031Y193640D01*
X624589D01*
X618760Y187811D01*
X605547D01*
X604596Y186860D01*
X601404D01*
X600453Y187811D01*
X561433D01*
X549073Y175451D01*
X513134D01*
X503983Y166300D01*
X484359D01*
X479816Y170843D01*
X469651D01*
X465108Y166300D01*
X457382D01*
X456500Y165418D01*
G01X469000Y784000D02*
X470000Y785000D01*
Y820500D01*
X474000Y824500D01*
X499500D01*
X500700Y825700D01*
Y828100D01*
G01X530800Y123900D02*
X516100D01*
X510100Y129900D01*
Y140828D01*
X509369Y141559D01*
G01X532978Y371023D02*
X534501Y369500D01*
X561300D01*
G01X519748Y768297D02*
X519795Y768250D01*
X521028D01*
X525778Y763500D01*
X542500D01*
X544000Y762000D01*
Y761000D01*
G01X515650Y764500D02*
X517898Y766748D01*
Y769198D01*
X518950Y770250D01*
X521150D01*
X526400Y765000D01*
X545000D01*
X547395Y762605D01*
Y761198D01*
G01X519906Y764900D02*
X522256D01*
X525156Y762000D01*
X539500D01*
X540500Y761000D01*
G01Y781000D02*
X542500Y783000D01*
Y803383D01*
X544350Y805233D01*
Y806767D01*
X542500Y808617D01*
Y821400D01*
X527700Y836200D01*
X527500D01*
G01X547173Y167987D02*
Y167973D01*
X553151Y173951D01*
X564187D01*
X573836Y183600D01*
X616671D01*
X624211Y191140D01*
X680660D01*
X690300Y181500D01*
X693000D01*
X693300Y181200D01*
G01X1359128Y167226D02*
X1356865Y169489D01*
X1354391D01*
X1354308Y169407D01*
X1350920D01*
X1345943Y164430D01*
X1338911D01*
X1328312Y153831D01*
X1317358D01*
X1314160Y150633D01*
X1312500Y148974D01*
Y27131D01*
X1275139Y-10230D01*
X1078851D01*
X1072021Y-3400D01*
X1070520Y-1900D01*
X1028333D01*
X1014545Y11888D01*
X974605D01*
X950670Y-12047D01*
X807733D01*
X794836Y850D01*
X786350D01*
X776167Y-9333D01*
X747873D01*
X746329Y-7789D01*
G01X865406Y745598D02*
X860158Y740350D01*
X841350D01*
X837000Y736000D01*
Y735500D01*
G01X868200Y116000D02*
X869000D01*
X871358Y113642D01*
X901732D01*
X903800Y115710D01*
Y124173D01*
X905243Y125616D01*
X905832D01*
X907506Y127290D01*
Y127879D01*
X909180Y129553D01*
X909769D01*
X911900Y131684D01*
Y141821D01*
X913780Y143701D01*
G01X846702Y117371D02*
X847071D01*
X854746Y125046D01*
X871893D01*
X873250Y126403D01*
G01X854400Y117500D02*
X855000D01*
X859970Y122470D01*
X872092D01*
G01X861300Y117800D02*
X898016D01*
X900369Y120153D01*
Y124679D01*
X901306Y125616D01*
X901895D01*
X904306Y128027D01*
Y128616D01*
X905243Y129553D01*
X905832D01*
X907506Y131227D01*
Y152238D01*
X906244Y153500D01*
X903981D01*
X901969Y155512D01*
G01X869406Y745531D02*
X862725Y738850D01*
X843850D01*
X840500Y735500D01*
G01X877000Y745000D02*
X867500Y735500D01*
X848000D01*
G01X873367Y745335D02*
Y745559D01*
X865158Y737350D01*
X847233D01*
X845383Y735500D01*
X844000D01*
G01X1030139Y30209D02*
X1027848Y32500D01*
X1018887D01*
X1014276Y37111D01*
X986578D01*
X977500Y46189D01*
Y54867D01*
X972250Y60117D01*
Y61983D01*
X970933Y63300D01*
X969067D01*
X968961Y63194D01*
X965836D01*
X964872Y64158D01*
X963338D01*
X963266Y64086D01*
X961353Y66000D01*
X935817D01*
X928250Y58433D01*
Y58250D01*
X924900Y54900D01*
X915600D01*
X907400Y46700D01*
X889100D01*
X883800Y41400D01*
G01X876470Y808710D02*
X877200Y809440D01*
X905536D01*
X906396Y810300D01*
G01X881720Y807390D02*
X905960D01*
X906450Y806900D01*
G01X874570Y811820D02*
X904225D01*
X906092Y813687D01*
G01X963700Y21700D02*
X958954D01*
X934881Y45773D01*
Y57322D01*
G01X970064Y18764D02*
X964428Y24400D01*
X959838D01*
X939064Y45174D01*
Y58104D01*
G01X1052600Y14400D02*
X1047869Y19131D01*
X1040906D01*
Y19150D01*
X1039404D01*
X1034879Y23675D01*
X1015380D01*
X1013464Y21759D01*
X995710D01*
X986658Y30811D01*
X963710D01*
X959877Y26978D01*
G01X1076970Y30411D02*
X1075661Y29102D01*
X1075099D01*
X1064384Y18387D01*
Y17583D01*
X1061669Y14868D01*
X1056959D01*
X1049676Y22151D01*
X1040798D01*
X1036273Y26676D01*
X1035701D01*
X1035700Y26675D01*
X1014136D01*
X1013323Y25862D01*
X995851D01*
X987901Y33812D01*
X987050D01*
X975162Y45700D01*
Y53584D01*
X970448Y58298D01*
X968115D01*
X964105Y62308D01*
G01X1082974Y14467D02*
X1074961Y22480D01*
X1070599D01*
X1065884Y17765D01*
Y14921D01*
X1064331Y13368D01*
X1056337D01*
X1049055Y20650D01*
X1040026D01*
X1035501Y25175D01*
X1014758D01*
X1013629Y24046D01*
X995545D01*
X987279Y32312D01*
X986304D01*
X972519Y46097D01*
Y52872D01*
X970750Y54641D01*
Y55045D01*
X968997Y56798D01*
X966998D01*
X963140Y60656D01*
X960306D01*
X959855Y61107D01*
G01X1002192Y113642D02*
X1013358D01*
X1016000Y111000D01*
Y109000D01*
X1015948Y108948D01*
Y108500D01*
G01X1037900D02*
X1038600Y107800D01*
Y105757D01*
X1036399Y103556D01*
X1007661D01*
X1000933Y110284D01*
X998879D01*
G01X1041300Y108500D02*
X1040600Y107800D01*
Y104928D01*
X1037228Y101556D01*
X1006832D01*
X1000104Y108284D01*
X998879D01*
G01X1001669Y114542D02*
X1015358D01*
X1019900Y110000D01*
Y108500D01*
G01X1034500D02*
X1033617D01*
X1030298Y105181D01*
X1027406D01*
X1026887Y105700D01*
X1013027D01*
X1007027Y111700D01*
X997500D01*
X995350Y113850D01*
G01X1022398Y115360D02*
X1027483Y110275D01*
Y108431D01*
G01X1048100Y108500D02*
X1047490Y109110D01*
Y112232D01*
X1043994Y115728D01*
X1032862D01*
X1029683Y118907D01*
Y119466D01*
G01X1044700Y108500D02*
X1045490Y109290D01*
Y111403D01*
X1043165Y113728D01*
X1032033D01*
X1027683Y118078D01*
Y119466D01*
G01X1018200Y116800D02*
X1024000Y111000D01*
Y108500D01*
G01X1030883Y108438D02*
X1029126Y106681D01*
X1013319D01*
X1007258Y112742D01*
X998174D01*
X996916Y114000D01*
G01X1354971Y167446D02*
Y166951D01*
X1354972Y166950D01*
Y162165D01*
X1348575Y155768D01*
X1340041D01*
X1336604Y152331D01*
X1319094D01*
X1314001Y147238D01*
Y145411D01*
X1314000Y17440D01*
X1284809Y-11751D01*
X1078251D01*
X1078235Y-11735D01*
X1078234D01*
X1076733Y-10235D01*
X1076314D01*
X1070279Y-4200D01*
X1069200D01*
G01X1143000Y242000D02*
X1158000Y257000D01*
Y284444D01*
X1171200Y297644D01*
Y341407D01*
X1217793Y388000D01*
X1264293D01*
X1266143Y389850D01*
X1286150D01*
X1289500Y386500D01*
G01X1147000Y242000D02*
X1159500Y254500D01*
Y283822D01*
X1172700Y297022D01*
Y340322D01*
X1218878Y386500D01*
X1264915D01*
X1266765Y388350D01*
X1282767D01*
X1283850Y387267D01*
Y384110D01*
X1282740Y383000D01*
G01X1282000Y386500D02*
X1278003D01*
X1273503Y382000D01*
X1219000D01*
X1174201Y337201D01*
Y296401D01*
X1161000Y283200D01*
Y252000D01*
X1151000Y242000D01*
G01X1282740Y350010D02*
X1290750Y342000D01*
X1291878D01*
X1293378Y340500D01*
X1362379D01*
X1385688Y317191D01*
Y184240D01*
X1383536Y182088D01*
Y176077D01*
X1383823Y175790D01*
Y170608D01*
X1379562Y166347D01*
X1361276D01*
X1349197Y154268D01*
X1340663D01*
X1331993Y145598D01*
X1318202D01*
X1316590Y147210D01*
G01X1317400Y143620D02*
X1332582D01*
X1341730Y152768D01*
X1349819D01*
X1361898Y164847D01*
X1380184D01*
X1385323Y169986D01*
Y175009D01*
X1387500Y177186D01*
Y317501D01*
X1363000Y342001D01*
X1361757Y342000D01*
X1297050D01*
X1293280Y345770D01*
G01X1340130Y145980D02*
X1345418Y151268D01*
X1350441D01*
X1362520Y163347D01*
X1380806D01*
X1389046Y171587D01*
Y318077D01*
X1363621Y343502D01*
X1362378Y343501D01*
X1361136D01*
X1361135Y343500D01*
X1299000D01*
X1292188Y350312D01*
X1290372D01*
X1289960Y349900D01*
G01X1339471Y139268D02*
Y142571D01*
X1346668Y149768D01*
X1351063D01*
X1363142Y161847D01*
X1380184D01*
X1380185Y161846D01*
X1381427D01*
X1390546Y170965D01*
Y318699D01*
X1364243Y345002D01*
X1361757D01*
X1361756Y345001D01*
X1360514D01*
X1360513Y345000D01*
X1301500D01*
X1299000Y347500D01*
G01X1322000Y276500D02*
X1326050Y280550D01*
X1353595D01*
X1353645Y280500D01*
X1364000D01*
G01X1336795Y685141D02*
X1336709Y685055D01*
X1336388D01*
X1331000Y679667D01*
Y662000D01*
G01X1351500Y675000D02*
X1348500Y672000D01*
X1336000D01*
X1334128Y673872D01*
Y674000D01*
G54D16*
X533010Y69803D03*
X535962Y64292D03*
Y49331D03*
X533010Y54843D03*
X541868Y69803D03*
X544821Y64292D03*
Y49331D03*
X541868Y54843D03*
X576317D03*
X585175D03*
X579269Y49331D03*
X588128D03*
X576317Y69803D03*
X585175D03*
X579269Y64292D03*
X588128D03*
X619624Y54843D03*
X628482D03*
X622577Y49331D03*
X631435D03*
X619624Y69803D03*
X628482D03*
X622577Y64292D03*
X631435D03*
X662931Y54843D03*
X671789D03*
X665884Y49331D03*
X662931Y69803D03*
X671789D03*
X665884Y64292D03*
X674742Y49331D03*
Y64292D03*
X1135372Y69803D03*
X1144230D03*
X1138324Y64292D03*
Y49331D03*
X1135372Y54843D03*
X1178679Y69803D03*
X1147183Y64292D03*
X1187537Y54843D03*
X1190490Y49331D03*
X1187537Y69803D03*
X1181631Y64292D03*
X1190490D03*
X1221986Y54843D03*
X1230844D03*
X1224939Y49331D03*
X1233797D03*
X1221986Y69803D03*
X1230844D03*
X1224939Y64292D03*
X1233797D03*
X1265293Y54843D03*
X1274151D03*
X1268246Y49331D03*
X1277104D03*
X1265293Y69803D03*
X1274151D03*
X1268246Y64292D03*
X1277104D03*
G54D26*
G01X221460Y335475D02*
G03X219682Y337025I-1778J-245D01*
G01X173537D01*
X168957Y341605D01*
X149144D01*
X147264Y339725D01*
X116163D01*
X115513Y340375D01*
X110252D01*
X109152Y341475D01*
X105709D01*
X92358Y354826D01*
X89145D01*
X84922Y359049D01*
X80200D01*
X75748Y363501D01*
X72799D01*
X53594Y382706D01*
Y384039D01*
X28149Y409484D01*
Y425541D01*
X15365Y438325D01*
Y521748D01*
X46939Y553322D01*
X47169D01*
X47172Y553325D01*
X48109D01*
X71209Y576425D01*
X72177D01*
X78052Y582300D01*
X85110D01*
X90988Y576422D01*
Y571765D01*
X98453Y564300D01*
X101430D01*
X102870Y565740D01*
G01X221460Y339875D02*
G02X219682Y338325I-1778J245D01*
G01X174076D01*
X169496Y342905D01*
X148605D01*
X146725Y341025D01*
X116702D01*
X116052Y341675D01*
X110791D01*
X109691Y342775D01*
X106248D01*
X92897Y356126D01*
X89684D01*
X85461Y360349D01*
X80739D01*
X76287Y364801D01*
X73338D01*
X54894Y383245D01*
Y384578D01*
X29449Y410023D01*
Y426080D01*
X16665Y438864D01*
Y521209D01*
X47478Y552022D01*
X47708D01*
X47711Y552025D01*
X48648D01*
X71748Y575125D01*
X72716D01*
X78591Y581000D01*
X84571D01*
X89688Y575883D01*
Y571226D01*
X97914Y563000D01*
X101210D01*
X102870Y561340D01*
G01X62400Y342700D02*
X63950Y341150D01*
Y339511D01*
X65196Y338265D01*
X70816Y334616D01*
X71052Y334565D01*
Y334566D01*
X75508Y333618D01*
X84084Y335442D01*
X85449Y335151D01*
X87205Y334011D01*
X92978Y325123D01*
X103442Y318329D01*
X107423Y317482D01*
X126983Y321641D01*
X132075Y320559D01*
X140989Y322450D01*
Y322449D01*
X149364Y324226D01*
X168305Y320200D01*
X179244Y313098D01*
X193605Y310044D01*
X204406Y312337D01*
X204407D01*
X222092Y316096D01*
X233836Y313600D01*
X262637Y319722D01*
X291858Y313511D01*
X299870Y315215D01*
X303217Y317388D01*
X308399Y318489D01*
X311759Y317775D01*
X335081Y302634D01*
X340552D01*
X341652Y301534D01*
G01X66800Y342700D02*
X65250Y341150D01*
Y340050D01*
X66019Y339281D01*
X71322Y335838D01*
X75508Y334948D01*
X84084Y336772D01*
X85956Y336373D01*
X88145Y334951D01*
X93918Y326063D01*
X103948Y319551D01*
X107423Y318812D01*
X126983Y322971D01*
X132075Y321889D01*
X149364Y325556D01*
X168811Y321422D01*
X179750Y314320D01*
X193605Y311374D01*
X222092Y317426D01*
X233836Y314930D01*
X262637Y321052D01*
X291858Y314841D01*
X299364Y316437D01*
X302711Y318610D01*
X308399Y319819D01*
X312265Y318997D01*
X335466Y303934D01*
X340552D01*
X341652Y305034D01*
G01X792000Y195778D02*
X791190Y196315D01*
G02X790500Y197600I851J1285D01*
G01Y199213D01*
G03X789658Y200765I-1851J0D01*
G01X771024Y212867D01*
G02X770873Y213013I300J461D01*
G01X763431Y223639D01*
X760770Y238752D01*
X764647Y260762D01*
X757818Y299500D01*
X690010Y396441D01*
X676592Y405836D01*
X668185Y407318D01*
X667617Y408129D01*
X665992Y408415D01*
X665181Y407848D01*
X663556Y408134D01*
X662988Y408945D01*
X661363Y409231D01*
X660552Y408664D01*
X658927Y408950D01*
X658360Y409761D01*
X656735Y410047D01*
X655924Y409479D01*
X654299Y409766D01*
X653731Y410577D01*
X652106Y410863D01*
X651295Y410295D01*
X646136Y411205D01*
X603273Y403648D01*
X602463Y404216D01*
X600838Y403930D01*
X600270Y403119D01*
X598645Y402832D01*
X597834Y403400D01*
X596209Y403114D01*
X595641Y402303D01*
X594016Y402016D01*
X593205Y402584D01*
X591580Y402297D01*
X591013Y401487D01*
X589388Y401200D01*
X588577Y401768D01*
X586952Y401481D01*
X586384Y400670D01*
X584759Y400384D01*
X558937Y404937D01*
X548240Y411883D01*
X548035Y412852D01*
X546651Y413750D01*
X545682Y413545D01*
X544299Y414443D01*
X544093Y415412D01*
X542709Y416310D01*
X541741Y416104D01*
X540357Y417003D01*
X540151Y417971D01*
X538767Y418870D01*
X537799Y418664D01*
X536415Y419563D01*
X536209Y420531D01*
X534825Y421430D01*
X533857Y421224D01*
X529260Y424209D01*
X501169Y430180D01*
X479480Y425570D01*
X462553Y429169D01*
X345007Y408441D01*
X328696Y411909D01*
X308065Y407524D01*
X298631Y409529D01*
X274633Y404428D01*
X249032Y409869D01*
X235603Y407502D01*
X223984Y399369D01*
Y399371D01*
X200392Y395340D01*
X174906Y400757D01*
X171302Y403097D01*
X167249Y403959D01*
X160394Y402501D01*
X158586Y402885D01*
X154433Y405582D01*
X145324Y407518D01*
X136769Y405700D01*
X134065Y406275D01*
X129325Y409353D01*
X112511Y433364D01*
X111560Y434315D01*
Y434316D01*
X111558Y434318D01*
X102060Y440896D01*
G03X100082Y441450I-1978J-3254D01*
G01X98129D01*
G02X97740Y441611I0J550D01*
G01X96351Y443000D01*
G01Y438600D02*
X97740Y439989D01*
G02X98129Y440150I389J-389D01*
G01X100082D01*
G02X101384Y439785I-1J-2508D01*
G02X101665Y439587I-1323J-2177D01*
G01X110718Y433318D01*
X111511Y432525D01*
X128258Y408606D01*
X128618Y408262D01*
X133559Y405053D01*
X136769Y404370D01*
X145324Y406188D01*
X153927Y404360D01*
X158080Y401663D01*
X160394Y401171D01*
X167249Y402629D01*
X170796Y401875D01*
X174400Y399535D01*
X200365Y394016D01*
X224494Y398138D01*
X236113Y406271D01*
X249009Y408544D01*
X274633Y403098D01*
X298631Y408199D01*
X308065Y406194D01*
X328696Y410579D01*
X344984Y407116D01*
X462530Y427844D01*
X479480Y424240D01*
X501169Y428850D01*
X528754Y422987D01*
X558450Y403702D01*
X584759Y399063D01*
X646136Y409884D01*
X676082Y404605D01*
X689076Y395507D01*
X756587Y298990D01*
X763326Y260762D01*
X759449Y238752D01*
X762200Y223129D01*
X766087Y217579D01*
X769807Y212267D01*
G03X770315Y211776I1517J1061D01*
G01X788949Y199675D01*
G02X789200Y199213I-300J-462D01*
G01Y197800D01*
G02X787600Y195804I-2219J140D01*
G01X799000Y196000D02*
G03X799900Y198173I-2173J2173D01*
G01Y198828D01*
X799899Y198827D01*
G03X799380Y200080I-1772J0D01*
G01Y200081D01*
X796205Y203256D01*
X791991D01*
X771073Y217903D01*
X765989Y225158D01*
X763545Y239036D01*
X767455Y261217D01*
X760463Y300886D01*
X689379Y402336D01*
X678647Y409852D01*
X645548Y415687D01*
X582174Y404512D01*
X561938Y408080D01*
X534751Y425731D01*
X497869Y433570D01*
X477569Y429255D01*
X462204Y432522D01*
X343939Y411670D01*
X335986Y413361D01*
X328034Y415050D01*
X308926Y410989D01*
X298054Y413300D01*
X273429Y408066D01*
X247398Y413597D01*
X233412Y411133D01*
X227345Y406884D01*
X220806Y402305D01*
Y402303D01*
X200878Y398791D01*
X177825Y403581D01*
X168875Y409393D01*
X166247Y409951D01*
X157057Y407998D01*
X145364Y410484D01*
X139000Y409130D01*
X136314Y409701D01*
X131603Y412777D01*
X114626Y437026D01*
X96138Y449807D01*
G03X94810Y450349I-1894J-2744D01*
G01X94809D01*
Y450350D01*
X92978D01*
G03X92589Y450189I0J-550D01*
G01X91200Y448800D01*
G01Y453200D02*
X92589Y451811D01*
G03X92978Y451650I389J389D01*
G01X94801D01*
G02X95031Y451631I8J-1306D01*
G02X96877Y450877I-788J-4567D01*
G01X96878D01*
X105451Y444950D01*
X106425Y445128D01*
X107782Y444189D01*
X107960Y443215D01*
X109317Y442277D01*
X110291Y442455D01*
X111648Y441516D01*
X111826Y440543D01*
X115557Y437963D01*
X115558Y437962D01*
Y437961D01*
X115561Y437958D01*
X132525Y413729D01*
X133599Y413027D01*
X136822Y410923D01*
X139000Y410460D01*
X145364Y411814D01*
X157057Y409328D01*
X166247Y411281D01*
X167831Y410944D01*
X169381Y410615D01*
X173854Y407710D01*
X178329Y404805D01*
X186113Y403188D01*
X186940Y403731D01*
X188556Y403395D01*
X189099Y402567D01*
X190714Y402231D01*
X191542Y402774D01*
X193158Y402439D01*
X193701Y401611D01*
X200898Y400115D01*
X220293Y403533D01*
X220296Y403536D01*
X232902Y412364D01*
X247421Y414922D01*
X273429Y409396D01*
X298054Y414630D01*
X308926Y412319D01*
X328034Y416380D01*
X343962Y412995D01*
X462227Y433847D01*
X477569Y430585D01*
X497869Y434900D01*
X535257Y426953D01*
X562424Y409315D01*
X582174Y405833D01*
X587788Y406823D01*
X588388Y407680D01*
X590013Y407967D01*
X590870Y407366D01*
X594120Y407939D01*
X594720Y408797D01*
X596345Y409083D01*
X597202Y408483D01*
X603226Y409545D01*
X603827Y410403D01*
X605452Y410689D01*
X606309Y410089D01*
X607934Y410375D01*
X608534Y411233D01*
X610159Y411519D01*
X611016Y410919D01*
X617349Y412035D01*
X617949Y412893D01*
X619574Y413179D01*
X620431Y412579D01*
X622056Y412865D01*
X622657Y413723D01*
X624282Y414009D01*
X625139Y413409D01*
X626764Y413695D01*
X627364Y414553D01*
X628989Y414839D01*
X629846Y414239D01*
X633148Y414821D01*
X633748Y415678D01*
X635373Y415965D01*
X636230Y415365D01*
X645548Y417008D01*
X656627Y415055D01*
X662323Y414051D01*
X670598Y412592D01*
X679157Y411083D01*
X690313Y403270D01*
X761694Y301396D01*
X768776Y261217D01*
X764866Y239036D01*
X767220Y225668D01*
X772006Y218837D01*
X792401Y204556D01*
X796744D01*
X800300Y201000D01*
G02X801200Y198827I-2173J-2173D01*
G01Y197760D01*
G03X801737Y196462I1835J-1D01*
G01X802200Y196000D01*
G01X110406Y417067D02*
G02X112570Y417092I1095J-1095D01*
G03X112598Y417064I2031J2003D01*
G01X112671Y416992D01*
X124277Y405386D01*
X127248Y400981D01*
X129068Y399752D01*
X129505Y399457D01*
X164679Y391982D01*
X175967Y394341D01*
X175969Y394340D01*
X203248Y388541D01*
X236383Y394386D01*
X250832Y391837D01*
X327946Y405456D01*
X342840Y402827D01*
X459339Y423328D01*
X459355Y423325D01*
X478984Y419152D01*
X500894Y423810D01*
X527816Y418086D01*
X556882Y399209D01*
X585017Y394248D01*
X610607Y398760D01*
X611476Y398151D01*
X613101Y398438D01*
X613709Y399307D01*
X615334Y399593D01*
X616203Y398985D01*
X617828Y399272D01*
X618436Y400140D01*
X620061Y400427D01*
X620930Y399819D01*
X622555Y400106D01*
X623163Y400974D01*
X644530Y404742D01*
X676977Y399021D01*
X685794Y392847D01*
X752722Y297261D01*
X759151Y260798D01*
X755380Y238957D01*
X758554Y220925D01*
X773017Y200266D01*
X786674Y190703D01*
X811971Y185327D01*
X829963Y173641D01*
X858157Y168669D01*
X858176Y168650D01*
X877800D01*
G01X113518Y420179D02*
G03Y417984I1097J-1098D01*
G01X125285Y406217D01*
X128185Y401917D01*
X130023Y400676D01*
X147342Y396996D01*
X164681Y393311D01*
X175969Y395670D01*
X203271Y389866D01*
X236383Y395707D01*
X250832Y393158D01*
X327946Y406777D01*
X342840Y404148D01*
X459346Y424650D01*
X459610Y424600D01*
X478984Y420482D01*
X500894Y425140D01*
X528322Y419308D01*
X557369Y400444D01*
X585017Y395569D01*
X644530Y406063D01*
X677487Y400252D01*
X686728Y393781D01*
X753953Y297771D01*
X760471Y260800D01*
X756700Y238959D01*
X759785Y221435D01*
X773951Y201200D01*
X787203Y191920D01*
X812477Y186549D01*
X830450Y174876D01*
X858382Y169950D01*
X877606D01*
G01X197420Y821701D02*
G02X198367Y819544I-2294J-2294D01*
G02X198370Y819407I-3241J-140D01*
G01Y812665D01*
G03X199483Y809978I3800J0D01*
G01X219792Y789669D01*
X263065Y759368D01*
X285290Y755449D01*
X294500Y749000D01*
X303585Y747398D01*
X312248Y748925D01*
X320128Y747537D01*
X344136Y751771D01*
X347032Y751260D01*
X371933Y733823D01*
X381269Y720490D01*
X382583Y713040D01*
X489478Y560377D01*
X683727Y424362D01*
X768256Y303676D01*
X775688Y261551D01*
X771703Y238941D01*
Y238937D01*
X773442Y228882D01*
X776784Y223737D01*
X787760Y216609D01*
X798413Y214345D01*
X810153Y206125D01*
X820533Y191370D01*
X835443Y180930D01*
X861383Y176357D01*
X871857D01*
G01X883900Y180146D02*
X872415D01*
X871861Y180700D01*
X860457D01*
X851344Y182306D01*
X831171Y196431D01*
X809759Y227009D01*
X807162Y241736D01*
X806278Y246746D01*
X804576Y256405D01*
X807954Y275569D01*
X803490Y300894D01*
X643749Y529029D01*
X403192Y697469D01*
X374066Y739066D01*
X347110Y757941D01*
X323829Y762046D01*
X298206Y757528D01*
X268771Y762718D01*
X232644Y788016D01*
X210700Y819354D01*
Y846495D01*
X198100Y866452D01*
Y869547D01*
G03X198064Y870010I-3011J-1D01*
G03X197218Y871676I-2975J-463D01*
G01X200620Y821701D02*
G03X199670Y819600I1848J-2101D01*
G01Y812666D01*
G03X200402Y810898I2500J0D01*
G01X220631Y790669D01*
X263575Y760599D01*
X285800Y756680D01*
X295010Y750231D01*
X303585Y748719D01*
X312248Y750246D01*
X320128Y748858D01*
X344136Y753092D01*
X347542Y752491D01*
X372867Y734757D01*
X382500Y721000D01*
X383814Y713550D01*
X490412Y561311D01*
X582521Y496815D01*
X583552Y496997D01*
X584904Y496051D01*
X585085Y495020D01*
X586437Y494074D01*
X587467Y494255D01*
X588819Y493309D01*
X589001Y492278D01*
X590352Y491332D01*
X591383Y491514D01*
X592735Y490567D01*
X592916Y489537D01*
Y489536D01*
X684661Y425296D01*
X769487Y304186D01*
X777009Y261551D01*
X773023Y238937D01*
X774678Y229366D01*
X777724Y224677D01*
X788266Y217831D01*
X798942Y215562D01*
X811086Y207060D01*
X821466Y192305D01*
X835953Y182161D01*
X861497Y177657D01*
X871318D01*
G01X890158Y190944D02*
Y191429D01*
G02X892300I1071J0D01*
G01Y189673D01*
G02X892287Y189460I-1772J1D01*
G01X892286Y189459D01*
G02X892105Y188865I-1759J211D01*
G02X891781Y188420I-1577J808D01*
G02X890769Y188000I-1013J1013D01*
G01X862706D01*
X855965Y189188D01*
X851953Y189895D01*
X836992Y200371D01*
X817476Y228246D01*
X811529Y261959D01*
X814130Y276713D01*
X808658Y307738D01*
X640149Y548395D01*
X396500Y719000D01*
X378527Y744669D01*
X345782Y767597D01*
X315827Y772879D01*
X298506Y769825D01*
X280500Y773000D01*
X267984Y781764D01*
X257663Y783583D01*
X239094Y796586D01*
X224602Y817282D01*
X224601Y845068D01*
X224600D01*
X212067Y866487D01*
Y872900D01*
G02X213005Y875163I3201J-1D01*
G01X213017Y875176D01*
G01X884000Y181446D02*
X872954D01*
X872400Y182000D01*
X860571D01*
X851854Y183537D01*
X832105Y197365D01*
X810990Y227519D01*
X805897Y256405D01*
X809275Y275569D01*
X804721Y301404D01*
X644683Y529963D01*
X404126Y698403D01*
X375000Y740000D01*
X347620Y759172D01*
X323829Y763367D01*
X298206Y758849D01*
X269281Y763949D01*
X233578Y788950D01*
X212000Y819765D01*
Y846872D01*
X199400Y866829D01*
Y870219D01*
G02X199710Y870969I1060J1D01*
G01X200418Y871676D01*
G01X894095Y190944D02*
G03X893578Y189696I1248J-1248D01*
G01Y189303D01*
G02X893263Y188272I-3051J368D01*
G02X892701Y187500I-2735J1400D01*
G01X892700D01*
X892699Y187499D01*
G02X890770Y186700I-1929J1929D01*
G01X862587D01*
X851443Y188664D01*
X836058Y199437D01*
X816245Y227736D01*
X810208Y261959D01*
X812809Y276713D01*
X807427Y307228D01*
X639215Y547461D01*
X395566Y718066D01*
X377593Y743735D01*
X345272Y766366D01*
X315827Y771558D01*
X298506Y768504D01*
X279990Y771769D01*
X267474Y780533D01*
X257153Y782352D01*
X238160Y795652D01*
X223302Y816872D01*
X223300Y844715D01*
X210767Y866134D01*
Y872882D01*
G03X209817Y875176I-3244J0D01*
G01X871444Y192400D02*
X862158D01*
X860711Y192654D01*
X856488Y193398D01*
X837053Y207007D01*
X828697Y218940D01*
X824069Y245187D01*
X829188Y274219D01*
X824692Y299678D01*
X653982Y543474D01*
X399504Y721662D01*
X381366Y747566D01*
X346082Y772272D01*
X260133Y787427D01*
X248366Y795666D01*
X238037Y810417D01*
X236043Y821721D01*
X237679Y831000D01*
X234953Y846463D01*
X223365Y863014D01*
Y872882D01*
G03X222415Y875176I-3244J0D01*
G01X871800Y193700D02*
X862272D01*
X860936Y193935D01*
X856998Y194629D01*
X837987Y207941D01*
X829928Y219450D01*
X825390Y245187D01*
X830509Y274219D01*
X825923Y300188D01*
X654916Y544408D01*
X400438Y722596D01*
X382300Y748500D01*
X346592Y773503D01*
X260643Y788658D01*
X249300Y796600D01*
X239268Y810927D01*
X237364Y821721D01*
X238142Y826136D01*
X239000Y831000D01*
X236184Y846973D01*
X224665Y863424D01*
Y872882D01*
G02X225615Y875176I3244J0D01*
G01X872100Y205400D02*
X863600D01*
X857239Y206521D01*
X848163Y212876D01*
X839122Y225788D01*
X836057Y243164D01*
X840242Y266898D01*
X837822Y280621D01*
Y280648D01*
X839989Y292935D01*
Y294899D01*
X837513Y308943D01*
X662763Y558511D01*
X393591Y746987D01*
X386728Y756789D01*
X343382Y787140D01*
X280818Y798174D01*
X262500Y811000D01*
X259500Y815284D01*
Y834500D01*
X258663Y839249D01*
X260465Y849475D01*
X257858Y864261D01*
X259311Y872500D01*
Y872882D01*
G02X260261Y875176I3244J0D01*
G01X238213D02*
G03X237263Y872882I2294J-2294D01*
G01Y866376D01*
X243500Y831000D01*
X242251Y823914D01*
X243285Y818046D01*
X251300Y806600D01*
X273643Y790955D01*
X349016Y777666D01*
X385100Y752400D01*
X393593Y740270D01*
X651627Y559595D01*
X833600Y299700D01*
X834708Y293415D01*
X832465Y280695D01*
X834566Y268787D01*
X830212Y244097D01*
X834246Y221222D01*
X840842Y211802D01*
X859759Y198557D01*
X865750Y197500D01*
X872900D01*
G01X872100Y204100D02*
X863486D01*
X856729Y205290D01*
X847229Y211942D01*
X837891Y225278D01*
X834736Y243164D01*
X838921Y266898D01*
X836522Y280507D01*
Y280751D01*
X836539Y280859D01*
X838689Y293049D01*
Y294785D01*
X836282Y308433D01*
X661829Y557577D01*
X392658Y746053D01*
X392657Y746054D01*
X385794Y755855D01*
X342872Y785909D01*
X280308Y796943D01*
X261566Y810066D01*
X258200Y814874D01*
Y834386D01*
X257342Y839249D01*
X259144Y849475D01*
X256537Y864261D01*
X258011Y872614D01*
Y872882D01*
G03X257061Y875176I-3244J0D01*
G01X872606Y196200D02*
X865636D01*
X859249Y197326D01*
X839908Y210868D01*
X833015Y220712D01*
X828891Y244097D01*
X833245Y268787D01*
X831144Y280695D01*
X833387Y293415D01*
X832369Y299190D01*
X650693Y558661D01*
X392659Y739336D01*
X384166Y751466D01*
X348506Y776435D01*
X273133Y789724D01*
X250366Y805666D01*
X242054Y817536D01*
X240930Y823914D01*
X242179Y831000D01*
X235963Y866258D01*
Y872882D01*
G03X235013Y875176I-3244J0D01*
G01X272859D02*
G03X271909Y872882I2294J-2294D01*
G01Y863352D01*
X273558Y853999D01*
X272000Y845165D01*
Y823000D01*
X272925Y817752D01*
X276358Y812850D01*
X285236Y806633D01*
X345305Y796044D01*
X382500Y770000D01*
X396856Y749497D01*
X666044Y561009D01*
X841084Y311030D01*
X844660Y290751D01*
X842500Y278500D01*
X844667Y266211D01*
X841970Y250915D01*
X847026Y222239D01*
X851247Y216211D01*
X859542Y210403D01*
X865800Y209300D01*
X873000D01*
G01X269659Y875176D02*
G02X270609Y872882I-2294J-2294D01*
G01Y863238D01*
X272237Y853999D01*
X270700Y845279D01*
Y822886D01*
X271694Y817242D01*
X275424Y811916D01*
X284726Y805402D01*
X344794Y794814D01*
X381566Y769066D01*
X395922Y748563D01*
X665110Y560075D01*
X839853Y310520D01*
X843339Y290751D01*
X841179Y278500D01*
X843346Y266211D01*
X840649Y250915D01*
X845795Y221729D01*
X850313Y215277D01*
X859032Y209172D01*
X865686Y208000D01*
X873000D01*
G01X285500Y866200D02*
G03X284550Y863906I2294J-2294D01*
G01Y857723D01*
X284986Y855251D01*
X284298Y851357D01*
X288591Y827013D01*
X290000Y825000D01*
X300224Y817841D01*
X331748Y812284D01*
X386473Y773967D01*
X394996Y761794D01*
X670774Y568693D01*
X842986Y322750D01*
X849061Y288311D01*
X847508Y279501D01*
X849896Y265959D01*
X847021Y249656D01*
X851391Y224875D01*
X855802Y218575D01*
X861933Y214282D01*
X867500Y213300D01*
X872300D01*
G01X282300Y866200D02*
G02X283250Y863906I-2294J-2294D01*
G01Y857609D01*
X283665Y855251D01*
X282977Y851357D01*
X287360Y826503D01*
X289066Y824066D01*
X299714Y816610D01*
X331238Y811053D01*
X385539Y773033D01*
X394059Y760863D01*
X669840Y567759D01*
X841755Y322240D01*
X847740Y288311D01*
X846187Y279501D01*
X848575Y265959D01*
X845700Y249656D01*
X850160Y224365D01*
X854868Y217641D01*
X861423Y213051D01*
X867386Y212000D01*
X872300D01*
G01X310955Y865676D02*
G03X310005Y863382I2294J-2294D01*
G01Y853707D01*
X306442Y833500D01*
X307457Y827747D01*
X312518Y824202D01*
X312523Y824198D01*
X325227Y821860D01*
X325459Y821698D01*
X325460D01*
X390000Y776500D01*
X396804Y766783D01*
X673721Y572891D01*
X847800Y324290D01*
X853455Y292234D01*
X851915Y283501D01*
X855000Y266000D01*
X851310Y245076D01*
X853990Y229884D01*
X860305Y220865D01*
X864463Y217953D01*
X869300Y217100D01*
X873300D01*
G01X307755Y865676D02*
G02X308705Y863382I-2294J-2294D01*
G01Y853821D01*
X305121Y833500D01*
X306269Y826990D01*
X312009Y822970D01*
X324713Y820632D01*
X389066Y775566D01*
X395869Y765849D01*
X672787Y571957D01*
X846569Y323780D01*
X852134Y292234D01*
X850594Y283501D01*
X853679Y266000D01*
X849989Y245076D01*
X852759Y229374D01*
X859371Y219931D01*
X863953Y216722D01*
X869186Y215800D01*
X873300D01*
G01X323253Y875176D02*
G03X322303Y872882I2294J-2294D01*
G01Y864500D01*
X332792Y849521D01*
X333502Y845499D01*
X333912Y843174D01*
X335000Y837000D01*
Y823000D01*
X337686Y819163D01*
X392103Y781068D01*
X399983Y769812D01*
X680066Y573576D01*
X852537Y327282D01*
X859333Y288766D01*
X857394Y277492D01*
X859412Y266044D01*
X855589Y244362D01*
X857875Y231401D01*
X862278Y225113D01*
X867022Y221791D01*
X870941Y221100D01*
X872400D01*
G01X320053Y875176D02*
G02X321003Y872882I-2294J-2294D01*
G01Y864090D01*
X331561Y849011D01*
X333700Y836886D01*
Y822590D01*
X336752Y818229D01*
X391169Y780134D01*
X399049Y768879D01*
X679132Y572643D01*
X851306Y326772D01*
X858013Y288763D01*
X856074Y277489D01*
X858091Y266044D01*
X854268Y244362D01*
X856644Y230891D01*
X861344Y224179D01*
X866512Y220560D01*
X870827Y219800D01*
X871600D01*
G01X873300Y223900D02*
X871700D01*
X862405Y233195D01*
X860692Y242914D01*
X864512Y264585D01*
X861855Y279654D01*
X863514Y289068D01*
X857401Y323739D01*
X678546Y579174D01*
X400513Y773859D01*
X394066Y783066D01*
X350245Y813750D01*
X346171Y819570D01*
Y840386D01*
X344989Y847087D01*
X334683Y861806D01*
X333601Y867944D01*
Y872882D01*
G03X332651Y875176I-3244J0D01*
G01X348450D02*
G03X347500Y872882I2294J-2294D01*
G01Y871218D01*
X348923Y863146D01*
X358627Y849287D01*
X360000Y841500D01*
Y819000D01*
X365837Y810665D01*
X398979Y787458D01*
X404736Y779236D01*
X679799Y586632D01*
X863237Y324659D01*
X869398Y289710D01*
X867065Y275785D01*
X869370Y264259D01*
X866093Y247859D01*
Y246222D01*
X868229Y234110D01*
X873285Y229054D01*
G01X873300Y225200D02*
X872240D01*
X863615Y233825D01*
X862013Y242914D01*
X865833Y264585D01*
X863176Y279654D01*
X864835Y289068D01*
X858632Y324249D01*
X679480Y580108D01*
X401447Y774793D01*
X395000Y784000D01*
X351179Y814684D01*
X347471Y819980D01*
Y840500D01*
X346220Y847597D01*
X335914Y862316D01*
X334901Y868062D01*
Y872882D01*
G02X335851Y875176I3244J0D01*
G01X345250D02*
G02X346200Y872882I-2294J-2294D01*
G01Y871101D01*
X347692Y862636D01*
X357396Y848777D01*
X358700Y841386D01*
Y818590D01*
X364903Y809731D01*
X398045Y786524D01*
X403802Y778302D01*
X678865Y585698D01*
X862006Y324149D01*
X868078Y289704D01*
X865743Y275764D01*
X868044Y264259D01*
X864793Y247988D01*
Y246108D01*
X867019Y233480D01*
X871846Y228653D01*
G01X874780Y232081D02*
X870509Y236351D01*
X868491Y247791D01*
Y249661D01*
X871410Y264259D01*
X870116Y270736D01*
X873150Y287956D01*
X865931Y328909D01*
X687275Y584057D01*
X405278Y781514D01*
X400236Y788715D01*
X389998Y795884D01*
X375833Y816115D01*
X370781Y844763D01*
X359769Y860490D01*
X358798Y865997D01*
Y872882D01*
G03X357848Y875176I-3244J0D01*
G01X361048D02*
G03X360098Y872882I2294J-2294D01*
G01Y866114D01*
X361000Y861000D01*
X372012Y845273D01*
X377064Y816625D01*
X390932Y796818D01*
X401170Y789649D01*
X406212Y782448D01*
X688209Y584991D01*
X867162Y329419D01*
X874471Y287956D01*
X871439Y270751D01*
X872736Y264259D01*
X869791Y249531D01*
Y247905D01*
X871718Y236982D01*
X875700Y233000D01*
G01X401300Y156715D02*
X402400Y155615D01*
X415125D01*
X471783Y143571D01*
X519717Y156661D01*
X528338Y154828D01*
X558536Y161245D01*
X573825Y171173D01*
X645985Y186444D01*
X714508Y171876D01*
X734917Y176215D01*
X735456Y177045D01*
X737070Y177388D01*
X737900Y176849D01*
X739514Y177192D01*
X740053Y178022D01*
X741667Y178365D01*
X742497Y177826D01*
X744111Y178169D01*
X744650Y179000D01*
X746264Y179343D01*
X747095Y178804D01*
X748709Y179147D01*
X749248Y179977D01*
X750862Y180320D01*
X751692Y179781D01*
X763730Y182340D01*
X777257D01*
G03X778807Y183890I0J1550D01*
G01Y179490D02*
G03X777257Y181040I-1550J0D01*
G01X763867D01*
X714508Y170546D01*
X645984Y185114D01*
X574331Y169950D01*
X559042Y160023D01*
X528338Y153498D01*
X519755Y155323D01*
X471821Y142233D01*
X414988Y154315D01*
X402400D01*
X401300Y153215D01*
G01X878300Y172500D02*
X860185D01*
X833672Y177175D01*
X816766Y189013D01*
X816634Y189201D01*
X816635D01*
X806366Y203866D01*
X801203Y207481D01*
X790234Y209415D01*
X773722Y220978D01*
X770949Y224933D01*
X769812Y226639D01*
X767652Y238908D01*
X771585Y261212D01*
X764319Y302428D01*
X682713Y418975D01*
X486851Y556118D01*
X437104Y627166D01*
X387353Y698215D01*
X379488Y703722D01*
X368625Y719236D01*
Y720706D01*
G03X367675Y723000I-3244J0D01*
G01X370875D02*
G03X369924Y720704I2296J-2296D01*
G01Y720600D01*
X369925D01*
Y719646D01*
X380422Y704656D01*
X388287Y699150D01*
X462976Y592484D01*
Y592483D01*
X475380Y574768D01*
X487785Y557052D01*
X513337Y539160D01*
X683647Y419909D01*
X765550Y302938D01*
X772906Y261212D01*
X768973Y238908D01*
X771046Y227133D01*
X772023Y225667D01*
X774655Y221912D01*
X790744Y210646D01*
X801713Y208712D01*
X807300Y204800D01*
X817700Y189947D01*
X834182Y178406D01*
X860303Y173800D01*
X878300D01*
G01X395694Y875176D02*
G03X394744Y872882I2294J-2294D01*
G01Y871451D01*
X395946Y864637D01*
X393184Y848973D01*
X394590Y841000D01*
Y821937D01*
X417529Y789179D01*
X693078Y596238D01*
X876007Y334995D01*
X883475Y292614D01*
X880928Y272193D01*
X880998Y263197D01*
G01X876850Y263188D02*
Y279266D01*
X878382Y287956D01*
X870537Y335309D01*
X695021Y585977D01*
X410520Y785186D01*
X398923Y801752D01*
X390000Y808000D01*
X380485Y821589D01*
X377463Y838729D01*
X382488Y867232D01*
X382146Y869172D01*
Y872882D01*
G02X383096Y875176I3244J0D01*
G01X392494D02*
G02X393444Y872882I-2294J-2294D01*
G01Y871335D01*
X394625Y864637D01*
X391863Y848973D01*
X393290Y840886D01*
Y821527D01*
X416595Y788245D01*
X692144Y595304D01*
X874776Y334485D01*
X882160Y292581D01*
X879627Y272269D01*
X879700Y262900D01*
G01X379896Y875176D02*
G02X380846Y872882I-2294J-2294D01*
G01Y869054D01*
X381167Y867232D01*
X376142Y838729D01*
X379254Y821079D01*
X389066Y807066D01*
X397989Y800818D01*
X409586Y784252D01*
X694087Y585043D01*
X869302Y334806D01*
X877061Y287956D01*
X875550Y279380D01*
Y262894D01*
G01X792760Y176043D02*
G03X791210Y177593I-1550J0D01*
G01X788609D01*
X783245Y174111D01*
X777566Y172904D01*
X770170Y174477D01*
X717891Y163647D01*
X647973Y178502D01*
X577298Y163545D01*
X549555Y145527D01*
X526986D01*
X516486Y147758D01*
X466163Y133783D01*
X419816Y143642D01*
X404700D01*
X403600Y142542D01*
G01Y146042D02*
X404700Y144942D01*
X419953D01*
X466122Y135121D01*
X516445Y149096D01*
X527123Y146827D01*
X549169D01*
X576792Y164768D01*
X647974Y179832D01*
X717894Y164976D01*
X751765Y171992D01*
X752308Y172820D01*
X753924Y173154D01*
X754751Y172611D01*
X756367Y172946D01*
X756911Y173773D01*
X758526Y174108D01*
X759354Y173564D01*
X760969Y173899D01*
X761513Y174727D01*
X763129Y175061D01*
X763956Y174518D01*
X765572Y174853D01*
X766115Y175680D01*
X767731Y176015D01*
X768558Y175471D01*
X770174Y175806D01*
X777566Y174234D01*
X782739Y175333D01*
X788224Y178893D01*
X791210D01*
G03X792760Y180443I0J1550D01*
G01X518686Y163800D02*
Y163900D01*
G03X517286Y165300I-1400J0D01*
G01X512876D01*
X507301Y159725D01*
X489625D01*
X482704Y152804D01*
X468413D01*
X463917Y157300D01*
X431261D01*
X413400Y175161D01*
Y315700D01*
X408850Y320250D01*
X405372D01*
G03X404040Y318918I0J-1332D01*
G01Y318900D01*
G01Y323300D02*
G03X405790Y321550I1750J0D01*
G01X409389D01*
X414700Y316239D01*
Y307931D01*
X415400Y307231D01*
Y305581D01*
X414700Y304881D01*
Y303231D01*
X415400Y302531D01*
Y300881D01*
X414700Y300181D01*
Y298531D01*
X415400Y297831D01*
Y296181D01*
X414700Y295481D01*
Y175700D01*
X431800Y158600D01*
X464456D01*
X468952Y154104D01*
X482165D01*
X489086Y161025D01*
X506762D01*
X512337Y166600D01*
X517200D01*
G03X518686Y168086I0J1486D01*
G01Y168200D01*
G01X420891Y875176D02*
G03X419941Y872882I2294J-2294D01*
G01Y870334D01*
X420892Y864943D01*
X418335Y850441D01*
X420000Y841000D01*
Y826335D01*
X422605Y811564D01*
X438378Y789035D01*
X703173Y603622D01*
X883457Y346138D01*
X892559Y294512D01*
X888850Y273479D01*
Y264868D01*
G01X408292Y875176D02*
G03X407342Y872882I2294J-2294D01*
G01Y870396D01*
X408462Y864045D01*
X405995Y850057D01*
X407504Y841500D01*
Y824148D01*
X408500Y818500D01*
X429313Y788775D01*
X696345Y601802D01*
X879564Y340134D01*
X888125Y291604D01*
X884851Y272583D01*
X884850D01*
Y264594D01*
G01X417691Y875176D02*
G02X418641Y872882I-2294J-2294D01*
G01Y870217D01*
X419571Y864943D01*
X417014Y850441D01*
X417886Y845496D01*
X418700Y840886D01*
Y826221D01*
X421374Y811054D01*
X429427Y799553D01*
X437444Y788101D01*
X702239Y602688D01*
X882226Y345628D01*
X891238Y294512D01*
X887550Y273593D01*
Y265162D01*
G01X405092Y875176D02*
G02X406042Y872882I-2294J-2294D01*
G01Y870279D01*
X407141Y864045D01*
X404674Y850057D01*
X406204Y841386D01*
Y824034D01*
X407269Y817990D01*
X428379Y787841D01*
X695411Y600868D01*
X878333Y339624D01*
X886805Y291601D01*
X883550Y272695D01*
Y264300D01*
G01X535962Y49331D02*
G03X535306Y49651I-792J-792D01*
G01X534533D01*
X533956Y49581D01*
X533922Y49559D01*
X533588Y49415D01*
X533388Y49323D01*
G03X533213Y49229I744J-1596D01*
G01X533210Y49227D01*
X533129Y49178D01*
G03X532871Y48974I745J-1207D01*
G01X530048Y46151D01*
G02X528661Y45270I-2442J2311D01*
G02X527600Y45100I-1057J3200D01*
G01X526700D01*
G02X525296Y45304I-2J4922D01*
G02X523230Y46531I1399J4709D01*
G01X521630Y48131D01*
G02X519952Y51065I4039J4257D01*
G02X519800Y52400I5753J1331D01*
G01Y55465D01*
G02X520670Y57885I3800J0D01*
G02X520913Y58152I2929J-2421D01*
G02X521706Y58894I4420J-3930D01*
G02X525700Y60262I3992J-5141D01*
G01X541600D01*
G03X547128Y62055I0J9418D01*
G03X547496Y62336I-5530J7623D01*
G01X550865Y65705D01*
X555547Y72653D01*
Y72657D01*
X558175Y87563D01*
X556123Y97218D01*
X558934Y110441D01*
X562580Y116056D01*
X567545Y139423D01*
X570660Y144220D01*
X574233Y146540D01*
X580618Y147897D01*
X595291Y144778D01*
X604537Y146744D01*
X629824Y163165D01*
X648117Y167054D01*
X717916Y153096D01*
X724332Y154379D01*
X736832Y151879D01*
X776421Y159796D01*
X830238Y148358D01*
X839804Y146325D01*
X858250Y150245D01*
X867971D01*
G01X868867Y156817D02*
X856346D01*
X837254Y153451D01*
X775363Y166605D01*
X735955Y158229D01*
X723447Y160730D01*
X717916Y159624D01*
X648665Y173472D01*
X576589Y158492D01*
X560175Y147833D01*
X557143Y143163D01*
X554012Y128442D01*
Y128186D01*
X553830Y128004D01*
X551309Y124122D01*
X534604Y113276D01*
X532751Y112882D01*
X522112Y105981D01*
X520537Y103554D01*
X520270Y102299D01*
X521266Y96651D01*
X519600Y87200D01*
Y85100D01*
X520234Y81505D01*
X522599Y78127D01*
X526206Y75601D01*
X530469Y76353D01*
X536439Y75300D01*
X538458Y73281D01*
G02Y70058I-1611J-1611D01*
G01X535950Y67550D01*
G03X535362Y66130I1420J-1420D01*
G01Y65600D01*
G03X535863Y64392I1709J1D01*
G01X535962Y64292D01*
G01X533010Y54843D02*
G02X534115Y54386I1J-1562D01*
G02X534700Y52974I-1412J-1412D01*
G01Y52747D01*
G02X534188Y51511I-1748J0D01*
G01X533597Y50920D01*
G02X533422Y50785I-1422J1662D01*
G02X533307Y50710I-1252J1794D01*
G02X532758Y50475I-1127J1875D01*
G01X532178Y50121D01*
X529078Y47021D01*
G02X527600Y46400I-1478J1448D01*
G01X526700D01*
G02X525667Y46550I-1J3622D01*
G02X524150Y47450I1034J3471D01*
G01X522300Y49300D01*
G02X521100Y52400I3404J3100D01*
G01Y55464D01*
G02X521673Y57057I2500J0D01*
G02X522504Y57866I4026J-3305D01*
G02X525700Y58962I3196J-4112D01*
G01X541600D01*
G03X547891Y61002I1J10718D01*
G03X548900Y61900I-3968J5474D01*
G01X551900Y64900D01*
X556780Y72156D01*
X559500Y87586D01*
X557453Y97218D01*
X560156Y109935D01*
X563802Y115550D01*
X568767Y138917D01*
X571600Y143280D01*
X574739Y145318D01*
X580618Y146567D01*
X595291Y143448D01*
X605043Y145522D01*
X630330Y161943D01*
X648125Y165726D01*
X717916Y151770D01*
X724332Y153053D01*
X736832Y150553D01*
X776413Y158468D01*
X829968Y147086D01*
X839804Y144995D01*
X858387Y148945D01*
X867971D01*
G01X868673Y158117D02*
X856232D01*
X837276Y154776D01*
X775363Y167935D01*
X735947Y159557D01*
X729695Y160807D01*
Y160808D01*
X723447Y162056D01*
X717917Y160950D01*
X717916D01*
X648660Y174799D01*
X576085Y159716D01*
X559235Y148773D01*
X555921Y143669D01*
X552740Y128713D01*
X550369Y125062D01*
X534098Y114498D01*
X532245Y114104D01*
X521172Y106921D01*
X519315Y104060D01*
X518945Y102322D01*
X519945Y96651D01*
X518300Y87314D01*
Y84986D01*
X519003Y80995D01*
X521665Y77193D01*
X525901Y74227D01*
X530469Y75032D01*
X535814Y74085D01*
X537538Y72361D01*
G02X537539Y70979I-691J-692D01*
G01X537313Y70753D01*
G02X534998Y69803I-2316J2348D01*
G01X533010D01*
G01X868209Y152899D02*
X857544D01*
X837779Y149413D01*
X776564Y162426D01*
X736616Y154437D01*
X724116Y156937D01*
X717916Y155697D01*
X648147Y169650D01*
X578636Y155629D01*
X563592Y145866D01*
X560558Y141194D01*
X552519Y95607D01*
X553915Y87676D01*
X551590Y74489D01*
X547350Y70249D01*
G02X547286Y70186I-4216J4219D01*
G01X545050Y67950D01*
G03X544241Y66283I2001J-2001D01*
G01Y65692D01*
G03X544821Y64292I1980J0D01*
G01X870539Y146338D02*
X859383D01*
X837888Y142548D01*
X805690Y148226D01*
X771943Y154975D01*
X736680Y147924D01*
X724178Y150423D01*
X717929Y149174D01*
X650005Y163493D01*
X631621Y159588D01*
X616259Y149609D01*
X612392Y143655D01*
X611235Y138206D01*
X612025Y134487D01*
X610647Y128000D01*
X609178Y125738D01*
X600912Y120371D01*
X574154Y114011D01*
X566298Y110692D01*
X562422Y104723D01*
X561699Y100621D01*
X563290Y91602D01*
X558164Y62529D01*
X552373Y54258D01*
X548877Y45377D01*
X548818Y44554D01*
G02X545753Y43635I-1707J123D01*
G01X545755Y43632D01*
X542385Y47932D01*
G02X541995Y50268I1955J1527D01*
G03X542217Y50673I-7442J4343D01*
G03X542451Y51163I-7654J3956D01*
G03X542543Y51381I-7892J3459D01*
G01Y51382D01*
G02X544419Y52174I1334J-542D01*
G01X544420Y52173D01*
G02X545213Y50297I-541J-1334D01*
G01X544821Y49331D01*
G01X579269D02*
G03X576567Y49527I-1521J-2248D01*
G03X575797Y48980I1233J-2552D01*
G01X571990Y45173D01*
G02X571002Y44469I-2593J2593D01*
G02X569401Y44100I-1602J3292D01*
G01X568600D01*
G02X567227Y44309I-4J4587D01*
G02X565363Y45437I1362J4354D01*
G01X563960Y46840D01*
G02X562143Y49720I5456J5455D01*
G02X561700Y52299I7281J2578D01*
G01Y54519D01*
G02X563480Y58820I6081J2D01*
G02X568020Y60700I4540J-4542D01*
G01X586990Y60601D01*
G03X590054Y61870I0J4333D01*
G01X593304Y65120D01*
X593380Y65228D01*
X595531Y66990D01*
X600513Y74104D01*
X602400Y84806D01*
Y99514D01*
X603331Y104799D01*
X608246Y111817D01*
X614423Y115829D01*
X650426Y123481D01*
X663980Y132282D01*
X692676Y137342D01*
X705416Y139890D01*
X717916Y137390D01*
X721054Y138018D01*
X738222Y134991D01*
X773172Y141980D01*
X838813Y130405D01*
X862425Y134569D01*
X871059D01*
G01X868015Y154199D02*
X857430D01*
X837801Y150738D01*
X776572Y163754D01*
X736616Y155763D01*
X724116Y158263D01*
X717916Y157023D01*
X648146Y170976D01*
X578136Y156855D01*
X562652Y146806D01*
X559323Y141681D01*
X551198Y95607D01*
X552594Y87676D01*
X550380Y75119D01*
X546430Y71169D01*
G02X543132Y69803I-3298J3298D01*
G01X541868D01*
G01X870539Y145038D02*
X859497D01*
X837888Y141227D01*
X805450Y146948D01*
X771943Y153649D01*
X736680Y146598D01*
X724178Y149097D01*
X717922Y147846D01*
X650006Y162164D01*
X632127Y158366D01*
X617199Y148669D01*
X615408Y145911D01*
X615407Y145909D01*
X613614Y143149D01*
X612565Y138206D01*
X613355Y134487D01*
X611869Y127494D01*
X610118Y124798D01*
X601432Y119157D01*
X574560Y112771D01*
X567172Y109649D01*
X563657Y104237D01*
X563020Y100621D01*
X564611Y91602D01*
X559395Y62019D01*
X553527Y53638D01*
X550160Y45085D01*
X550115Y44461D01*
G02X544726Y42837I-3004J216D01*
G01X544721Y42843D01*
X541361Y47130D01*
Y47131D01*
G02X540766Y50692I2979J2328D01*
G02X540872Y50924I1260J-436D01*
G03X541259Y51684I-6315J3694D01*
G03X541868Y54843I-6703J2930D01*
G01X576317D02*
G02X577066Y51214I-83J-1909D01*
G01X576001Y50699D01*
G03X574877Y49900I1800J-3723D01*
G01X571069Y46092D01*
G02X570433Y45638I-1671J1668D01*
G02X569400Y45400I-1033J2123D01*
G01X568600D01*
G02X566276Y46362I-1J3286D01*
G01X564882Y47758D01*
G02X563000Y52300I4542J4543D01*
G01Y54520D01*
G02X564400Y57900I4780J0D01*
G02X568017Y59399I3620J-3622D01*
G01X586986Y59301D01*
G03X590974Y60950I5J5634D01*
G01X594303Y64280D01*
X594342Y64334D01*
X596494Y66097D01*
X601744Y73594D01*
X603700Y84686D01*
Y99400D01*
X604562Y104289D01*
X609166Y110864D01*
X614929Y114607D01*
X650932Y122259D01*
X664467Y131047D01*
X692916Y136064D01*
X705416Y138564D01*
X717916Y136064D01*
X721069Y136695D01*
X738237Y133668D01*
X773187Y140657D01*
X806001Y134870D01*
Y134869D01*
X838813Y129084D01*
X862539Y133269D01*
X871047D01*
G01X554750Y875176D02*
G03X553800Y872882I2294J-2294D01*
G01Y866923D01*
X564405Y851777D01*
X566200Y841600D01*
Y824500D01*
X567465Y817325D01*
X894871Y349745D01*
X899991Y320710D01*
X898402Y311701D01*
X901038Y296758D01*
X896775Y272581D01*
Y264300D01*
G01X892750Y264250D02*
Y272581D01*
X896973Y296534D01*
X893996Y313410D01*
X891800Y343642D01*
X567902Y806216D01*
X567900Y806218D01*
X567888D01*
X563629Y810477D01*
X553700Y824658D01*
Y842000D01*
X552442Y849130D01*
X541201Y865184D01*
Y872882D01*
G02X542151Y875176I3244J0D01*
G01X551550D02*
G02X552500Y872882I-2294J-2294D01*
G01Y866512D01*
X563174Y851267D01*
X564900Y841486D01*
Y824386D01*
X566234Y816815D01*
X893640Y349235D01*
X898670Y320710D01*
X897081Y311701D01*
X899717Y296758D01*
X895475Y272695D01*
Y264300D01*
G01X538951Y875176D02*
G02X539901Y872882I-2294J-2294D01*
G01Y864774D01*
X551211Y848620D01*
X552400Y841886D01*
Y824248D01*
X562629Y809638D01*
X566929Y805337D01*
X890529Y343190D01*
X892704Y313250D01*
X895652Y296534D01*
X891450Y272695D01*
Y264250D01*
G01X567348Y875176D02*
G03X566398Y872882I2294J-2294D01*
G01Y863913D01*
X577543Y847996D01*
X578900Y840300D01*
Y822834D01*
X581846Y806128D01*
X899153Y352975D01*
X904469Y322826D01*
Y322825D01*
X902536Y311860D01*
X905081Y297427D01*
X900700Y272581D01*
Y264400D01*
G01X564148Y875176D02*
G02X565098Y872882I-2294J-2294D01*
G01Y863502D01*
X576312Y847486D01*
X577600Y840186D01*
Y822720D01*
X580615Y805618D01*
X897922Y352465D01*
X903148Y322825D01*
X901215Y311860D01*
X903760Y297427D01*
X899400Y272695D01*
Y264400D01*
G01X871274Y141069D02*
X860253D01*
X837335Y137028D01*
X804335Y142848D01*
X771502Y149415D01*
X735366Y142187D01*
X722314Y144797D01*
X717916Y143917D01*
X705506Y146399D01*
X660011Y137296D01*
X654048Y138564D01*
X650581Y140815D01*
X648929Y143358D01*
X647543Y149878D01*
X644949Y153872D01*
X643579Y154762D01*
X638723Y155794D01*
X635320Y155070D01*
X622320Y146631D01*
X620696Y144130D01*
X617190Y127636D01*
X613837Y122472D01*
X599285Y112777D01*
X597910Y110805D01*
X595089Y94782D01*
X596156Y88733D01*
X594644Y80158D01*
X593921Y78223D01*
X591300Y75300D01*
X584787Y73123D01*
X582661Y71743D01*
X581176Y69424D01*
X580577Y68825D01*
X580578Y68824D01*
X578622Y66868D01*
G03X579269Y64292I1094J-1094D01*
G01X588128D02*
G02X587479Y65859I1567J1567D01*
G01Y66549D01*
G02X588024Y67865I1861J0D01*
G01X588832Y68672D01*
G03X588834Y68673I-1156J2315D01*
G03X589740Y69260I-923J2417D01*
G01X598130Y77649D01*
X600131Y88993D01*
X599228Y94106D01*
X601573Y107407D01*
X605201Y112591D01*
X612124Y117437D01*
X648147Y125097D01*
X662945Y134706D01*
X692916Y139990D01*
X705416Y142490D01*
X717916Y139990D01*
X721477Y140702D01*
X737519Y137874D01*
X772265Y144811D01*
X838494Y133130D01*
X861302Y137151D01*
X871480D01*
G01X588128Y49331D02*
X588458Y50258D01*
G03X585695Y51241I-1381J492D01*
G01Y51240D01*
G02X585086Y49889I-8555J3044D01*
G03X585126Y48597I1107J-612D01*
G01X589873Y43168D01*
G03X593466Y44531I1372J1800D01*
G02X596125Y55031I98827J-19440D01*
G01X597124Y58246D01*
G02X599546Y63084I15868J-4918D01*
G01X604150Y70461D01*
X606750Y85200D01*
Y86900D01*
X605824Y92149D01*
X605700Y99100D01*
X607435Y104404D01*
X610385Y108618D01*
X614221Y111303D01*
X618049Y112890D01*
X651307Y119961D01*
X664327Y128416D01*
X692676Y133415D01*
X705416Y135963D01*
X718501Y133347D01*
X721407Y133965D01*
X729821Y132481D01*
X737760Y131081D01*
X763142Y135555D01*
X781848Y132259D01*
X793222Y134575D01*
X839474Y126418D01*
X863016Y130571D01*
X863035Y130590D01*
X871338D01*
G01X576317Y69803D02*
G03X579757Y69844I1699J1782D01*
G01X580157Y70244D01*
X581717Y72681D01*
X584218Y74304D01*
X590561Y76425D01*
X592789Y78908D01*
X593384Y80501D01*
X594835Y88733D01*
X593768Y94782D01*
X596679Y111313D01*
X598358Y113723D01*
X612892Y123406D01*
X615968Y128142D01*
X619474Y144636D01*
X621380Y147571D01*
X634814Y156292D01*
X638723Y157124D01*
X644085Y155984D01*
X645889Y154812D01*
X648765Y150384D01*
X650151Y143865D01*
X650836Y142811D01*
X651521Y141756D01*
Y141755D01*
X654554Y139786D01*
X660019Y138624D01*
X705506Y147725D01*
X717916Y145243D01*
X722314Y146123D01*
X735366Y143513D01*
X771502Y150741D01*
X804575Y144126D01*
X837335Y138349D01*
X860136Y142369D01*
X871274D01*
G01X585175Y69803D02*
G03X585665Y69600I490J490D01*
G01X587422D01*
G03X588820Y70179I0J1977D01*
G01X596920Y78279D01*
X598810Y88993D01*
X597907Y94106D01*
X600342Y107917D01*
X604267Y113525D01*
X611595Y118654D01*
X647641Y126319D01*
X662458Y135941D01*
X692676Y141268D01*
X705416Y143816D01*
X717916Y141316D01*
X721462Y142025D01*
X737504Y139197D01*
X772250Y146134D01*
X838494Y134451D01*
X861077Y138432D01*
X861096Y138451D01*
X871480D01*
G01X585175Y54843D02*
G02X584470Y51676I-13153J1266D01*
G02X583947Y50519I-7326J2615D01*
G01X583948Y50518D01*
G03X584029Y47899I2245J-1241D01*
G03X584147Y47741I1118J712D01*
G01X588970Y42224D01*
G03X594742Y44280I2275J2744D01*
G02X597367Y54644I97550J-19193D01*
G01Y54646D01*
X598366Y57861D01*
G02X600599Y62320I14625J-4535D01*
G01X600625Y62357D01*
X605387Y69986D01*
X608069Y85191D01*
X608050Y85300D01*
Y87014D01*
X607123Y92274D01*
X607004Y98904D01*
X608611Y103816D01*
X611319Y107684D01*
X614851Y110156D01*
X618436Y111643D01*
X651813Y118739D01*
X664814Y127181D01*
X692916Y132137D01*
X705416Y134637D01*
X718509Y132019D01*
X721430Y132640D01*
X737760Y129760D01*
X763142Y134234D01*
X781866Y130935D01*
X793239Y133251D01*
X839474Y125097D01*
X863244Y129290D01*
X871338D01*
G01X579947Y875176D02*
G03X578996Y872882I2293J-2295D01*
G01X578997D01*
Y863932D01*
X590547Y847437D01*
X591700Y840900D01*
Y812805D01*
X593500Y802600D01*
X623823Y759294D01*
X662500Y732213D01*
X908805Y380452D01*
X914762Y346673D01*
X907500Y305500D01*
X908952Y297264D01*
X904600Y272581D01*
Y264400D01*
G01X576747Y875176D02*
X577466Y874456D01*
G02X577697Y873900I-556J-557D01*
G01Y863522D01*
X589316Y846927D01*
X590400Y840786D01*
Y812691D01*
X592269Y802090D01*
X622889Y758360D01*
X661566Y731279D01*
X907574Y379942D01*
X913441Y346673D01*
X906179Y305500D01*
X907631Y297264D01*
X903300Y272695D01*
Y264400D01*
G01X592545Y875176D02*
G03X591595Y872882I2294J-2294D01*
G01Y866759D01*
X602531Y851140D01*
X604301Y841100D01*
Y825341D01*
X911715Y386308D01*
X919247Y343591D01*
X912664Y306250D01*
X915014Y292920D01*
X911914Y275338D01*
X912400Y272581D01*
Y264900D01*
G01X589345Y875176D02*
G02X590295Y872882I-2294J-2294D01*
G01Y866348D01*
X601300Y850630D01*
X603001Y840986D01*
Y824931D01*
X910484Y385798D01*
X917926Y343591D01*
X911343Y306250D01*
X913693Y292920D01*
X910593Y275338D01*
X911100Y272467D01*
Y265194D01*
G01X601944Y875176D02*
G02X602894Y872882I-2294J-2294D01*
G01Y866970D01*
X605536Y863196D01*
X624669Y849799D01*
X626783Y846780D01*
X628000Y839886D01*
Y822547D01*
X649680Y791583D01*
X655505Y758549D01*
X913961Y389435D01*
X922066Y343471D01*
X915425Y305808D01*
X917469Y294213D01*
X914367Y276621D01*
X915100Y272467D01*
Y264994D01*
G01X622577Y49331D02*
G02X622506Y51516I1986J1158D01*
G01X622789Y52083D01*
G02X623190Y52714I3268J-1634D01*
G03X623744Y54515I-2041J1614D01*
G02X625429Y57377I2914J211D01*
G01X626153Y57726D01*
G02X627618Y58295I4342J-9008D01*
G01X634152Y60257D01*
X640684Y65824D01*
X640779Y65959D01*
Y65960D01*
X644381Y71102D01*
X649240Y98658D01*
X654390Y106012D01*
X669318Y116466D01*
X705437Y122835D01*
X718873Y120465D01*
X722604Y121258D01*
X737877Y118012D01*
X741979Y117289D01*
X758390Y120183D01*
X781135Y116172D01*
X805148Y120409D01*
X828451Y116301D01*
X844678Y104934D01*
X872310Y100062D01*
X888140Y102853D01*
X893348Y101935D01*
X908145Y104545D01*
X915204Y109324D01*
X915636Y109816D01*
X915638Y109817D01*
G01X622577Y64292D02*
G02X623487Y68527I3732J1413D01*
G01X624832Y69872D01*
X626762Y72890D01*
X628529Y74165D01*
X634100Y75300D01*
X636500Y77300D01*
X638455Y80604D01*
X639734Y87336D01*
X637920Y96497D01*
X639864Y104342D01*
X641120Y106135D01*
X667532Y123743D01*
X693300Y128287D01*
X697220Y129070D01*
X705930Y130606D01*
X718956Y128002D01*
X721957Y128607D01*
X739409Y124898D01*
X762435Y129794D01*
X780442Y125965D01*
X794556Y128965D01*
X831958Y122370D01*
X844047Y113906D01*
X874762Y108316D01*
X888033Y110655D01*
X894698Y109480D01*
X906112Y111492D01*
X907172Y112044D01*
G01X631435Y64292D02*
G02X632053Y68152I3326J1447D01*
G01Y68153D01*
G02X632195Y68304I2712J-2408D01*
G01X641426Y77533D01*
X645220Y99073D01*
X651649Y108255D01*
X668616Y120134D01*
X706000Y126726D01*
X719971Y124262D01*
X722748Y124853D01*
X739696Y121250D01*
X757125Y124955D01*
X782994Y120348D01*
X803251Y123921D01*
X831106Y119009D01*
X844962Y109307D01*
X873533Y104217D01*
X888813Y106911D01*
X893875Y106019D01*
Y106018D01*
X894100Y105979D01*
X907792Y108394D01*
X913453Y112153D01*
G01X920766Y110966D02*
X912573Y102773D01*
X899010Y93275D01*
X896220Y92413D01*
X893986Y93260D01*
X889544Y92372D01*
X875585Y95164D01*
X844468Y100650D01*
X825894Y113653D01*
X805463Y117254D01*
X779506Y112678D01*
X758063Y116459D01*
X733554Y112137D01*
X731702Y110841D01*
X718564Y108524D01*
X714318Y109427D01*
X706218Y107706D01*
X680238Y89876D01*
X666442Y87444D01*
X656400Y89100D01*
X653701Y88624D01*
X652205Y87577D01*
X651405Y86434D01*
X648267Y68640D01*
X643447Y61755D01*
X633800Y55000D01*
X632800Y54000D01*
Y53999D01*
X631107Y52306D01*
G03X630653Y51210I1096J-1096D01*
G01Y50982D01*
G03X631268Y49498I2099J1D01*
G01X631435Y49331D01*
G01X619624Y54843D02*
X619166Y53278D01*
G02X619078Y53056I-1280J379D01*
G01X619025Y52949D01*
G03X619573Y51305I1097J-548D01*
G01X619574Y51304D01*
G03X621219Y51851I549J1096D01*
G01X621626Y52665D01*
G02X622170Y53520I4430J-2218D01*
G03X622447Y54421I-1022J807D01*
G02X624868Y58550I4211J305D01*
G01X625588Y58898D01*
G02X627244Y59541I4906J-10180D01*
G01X633517Y61424D01*
X639714Y66706D01*
X643150Y71612D01*
X648009Y99168D01*
X653456Y106946D01*
X668808Y117697D01*
X705437Y124156D01*
X718850Y121790D01*
X722604Y122588D01*
X738125Y119289D01*
X741979Y118610D01*
X758390Y121504D01*
X781135Y117493D01*
X805148Y121730D01*
X828961Y117532D01*
X845188Y106165D01*
X872310Y101383D01*
X888140Y104174D01*
X893348Y103256D01*
X907646Y105778D01*
X914337Y110307D01*
X914659Y110674D01*
G01X619624Y69803D02*
G03X622138Y69018I1463J266D01*
G01X623812Y70692D01*
X625800Y73800D01*
X627995Y75383D01*
X633519Y76509D01*
X635495Y78155D01*
X635662Y78438D01*
X635782Y78641D01*
X635968Y78955D01*
X637220Y81070D01*
X637219D01*
X638409Y87331D01*
X636588Y96529D01*
X638660Y104890D01*
X640195Y107081D01*
X667037Y124977D01*
X693060Y129565D01*
X696980Y130348D01*
X705945Y131929D01*
X718955Y129328D01*
X721964Y129935D01*
X739409Y126228D01*
X762435Y131124D01*
X780442Y127295D01*
X794533Y130290D01*
X832468Y123601D01*
X844560Y115134D01*
X874766Y109637D01*
X888033Y111976D01*
X894698Y110801D01*
X905689Y112738D01*
X906571Y113197D01*
G01X628482Y69803D02*
G03X631083Y69020I1483J216D01*
G02X631276Y69224I3674J-3283D01*
G01X640216Y78163D01*
X643989Y99583D01*
X650715Y109189D01*
X668106Y121365D01*
X706000Y128047D01*
X719948Y125587D01*
X722748Y126183D01*
X739696Y122580D01*
X757103Y126280D01*
X782995Y121669D01*
X803251Y125242D01*
X831616Y120240D01*
X845473Y110537D01*
X873534Y105538D01*
X888813Y108232D01*
X894100Y107300D01*
X907298Y109627D01*
X912277Y112943D01*
X912750Y113247D01*
Y113248D01*
X912752Y113249D01*
G01X919846Y111885D02*
X911734Y103773D01*
X898431Y94457D01*
X896263Y93787D01*
X894098Y94609D01*
X889544Y93698D01*
X875825Y96442D01*
X844978Y101881D01*
X826404Y114884D01*
X805463Y118575D01*
X779506Y113999D01*
X758063Y117780D01*
X733044Y113368D01*
X731192Y112072D01*
X718587Y109849D01*
X714318Y110757D01*
X705695Y108924D01*
X679734Y91108D01*
X666435Y88763D01*
X656393Y90419D01*
X653191Y89855D01*
X651271Y88511D01*
X650174Y86944D01*
X647036Y69150D01*
X642513Y62689D01*
X632961Y56000D01*
X630564Y53603D01*
G02X628482Y54843I-884J884D01*
G01X605144Y875176D02*
G03X604194Y872882I2294J-2294D01*
G01Y867380D01*
X606470Y864130D01*
X625603Y850733D01*
X628014Y847290D01*
X629300Y840000D01*
Y822957D01*
X650911Y792093D01*
X656736Y759059D01*
X915192Y389945D01*
X923387Y343471D01*
X916746Y305808D01*
X918790Y294213D01*
X915688Y276621D01*
X916400Y272581D01*
Y264700D01*
G01X614542Y875176D02*
G02X615492Y872882I-2294J-2294D01*
G01Y868201D01*
X618882Y863359D01*
X635866Y851466D01*
X646005Y836986D01*
X652393Y800761D01*
X910527Y432106D01*
X926070Y343960D01*
X919308Y305611D01*
X921179Y295000D01*
X918053Y277272D01*
X918900Y272467D01*
Y264700D01*
G01X630340Y875176D02*
G03X629390Y872882I2294J-2294D01*
G01Y866699D01*
X631000Y864400D01*
X635696Y861111D01*
X646647Y859180D01*
X647920Y858288D01*
X658035Y851205D01*
X663054Y844038D01*
X665000Y833000D01*
X663898Y826750D01*
X670426Y789730D01*
X914827Y440692D01*
X931688Y345072D01*
X924954Y306880D01*
X926670Y297146D01*
X923319Y278144D01*
X924300Y272581D01*
Y264700D01*
G01X617742Y875176D02*
G03X616792Y872882I2294J-2294D01*
G01Y868611D01*
X619816Y864293D01*
X636800Y852400D01*
X647236Y837496D01*
X653624Y801271D01*
X911758Y432616D01*
X927391Y343960D01*
X920629Y305611D01*
X922500Y295000D01*
X919374Y277272D01*
X920200Y272581D01*
Y264700D01*
G01X627140Y875176D02*
G02X628090Y872882I-2294J-2294D01*
G01Y866289D01*
X630066Y863466D01*
X635186Y859880D01*
X646137Y857949D01*
X647174Y857223D01*
X657101Y850271D01*
X661823Y843528D01*
X663679Y833000D01*
X662577Y826750D01*
X669195Y789220D01*
X913596Y440182D01*
X930367Y345072D01*
X923633Y306880D01*
X925349Y297146D01*
X921998Y278144D01*
X923000Y272467D01*
Y264994D01*
G01X665884Y49331D02*
G02X666064Y51429I12317J0D01*
G02X666560Y52838I4421J-765D01*
G01X666564Y52844D01*
X669381Y56671D01*
X669393Y56677D01*
X670471Y57296D01*
X671090Y57651D01*
X672785Y58625D01*
X684261Y62119D01*
X697785Y64997D01*
X713161Y61727D01*
X728276Y64391D01*
X769775Y93461D01*
X784649Y96620D01*
X794309Y94567D01*
X810603Y98031D01*
X813690Y102787D01*
X817484Y103594D01*
X820805Y102889D01*
X842879Y88555D01*
X852360Y86883D01*
X866832Y76749D01*
X880538Y74007D01*
X910258Y80336D01*
X916303Y84261D01*
X917099Y85487D01*
X917470Y87227D01*
X924581Y98178D01*
X932692Y103448D01*
X934430Y106124D01*
Y112005D01*
G01X665884Y64292D02*
X664974Y65989D01*
G02X665199Y66734I485J260D01*
G01X665483Y66886D01*
G03X665981Y67276I-861J1612D01*
G01X668443Y70017D01*
X669713Y72876D01*
X671779Y74360D01*
X677436Y75484D01*
X682054Y78718D01*
X682055D01*
X682060Y78719D01*
X682077Y78722D01*
X683923Y79114D01*
X717727Y71929D01*
X726500Y73794D01*
X728006Y74773D01*
X743258Y98260D01*
X753555Y105471D01*
X775817Y109397D01*
X782670Y108188D01*
X806258Y113202D01*
X823498Y110164D01*
X842632Y96768D01*
X867375Y92405D01*
X889209Y88038D01*
X892591Y88715D01*
X896055Y87415D01*
X903448Y89825D01*
X910305Y94630D01*
X910309Y94636D01*
X912874Y98292D01*
X915340Y100018D01*
X915348Y100023D01*
X915552Y100160D01*
X916757Y101898D01*
X924005Y109146D01*
G01X662931Y54843D02*
X662473Y53278D01*
G02X662385Y53056I-1280J379D01*
G01X662332Y52949D01*
G03X662873Y51291I1100J-558D01*
G01X662874Y51290D01*
G03X664526Y51851I549J1096D01*
G01X665179Y53156D01*
X665464Y53544D01*
X665512Y53609D01*
X665516Y53615D01*
X665515D01*
X668495Y57663D01*
X668496Y57662D01*
X668740Y57802D01*
X668745Y57805D01*
X672265Y59826D01*
X683936Y63379D01*
X697785Y66327D01*
X713184Y63052D01*
X727766Y65622D01*
X769246Y94678D01*
X769505Y94733D01*
X769506D01*
Y94734D01*
X784649Y97950D01*
X794309Y95897D01*
X809806Y99191D01*
X812893Y103947D01*
X817484Y104924D01*
X819753Y104442D01*
X821311Y104111D01*
X832338Y96950D01*
X843366Y89790D01*
X852870Y88114D01*
X867355Y77971D01*
X880530Y75335D01*
X909752Y81558D01*
X915363Y85201D01*
X915877Y85994D01*
X916248Y87734D01*
X923641Y99118D01*
X931752Y104388D01*
X933130Y106510D01*
Y112005D01*
G01X662931Y69803D02*
X663789Y68201D01*
G03X664585Y67880I590J316D01*
G01X664870Y68033D01*
Y68034D01*
G03X665014Y68145I-245J466D01*
G01X666177Y69440D01*
X667338Y70733D01*
X668668Y73726D01*
X671249Y75581D01*
X676914Y76706D01*
X681544Y79949D01*
X681829Y79999D01*
X683923Y80444D01*
X717727Y73259D01*
X725992Y75016D01*
X727066Y75713D01*
X742305Y99180D01*
X753045Y106702D01*
X775817Y110718D01*
X782647Y109513D01*
X806235Y114527D01*
X824008Y111395D01*
X843142Y97999D01*
X867600Y93686D01*
X867624D01*
X867630Y93680D01*
X889209Y89364D01*
X892700Y90063D01*
X896085Y88793D01*
X902860Y91002D01*
X909372Y95564D01*
X909371D01*
X911939Y99224D01*
X911938Y99225D01*
X914594Y101084D01*
X914624Y101104D01*
X915755Y102735D01*
X923085Y110065D01*
G01X926900Y265120D02*
Y272695D01*
X931254Y297397D01*
X928679Y312000D01*
X934805Y346742D01*
X918166Y441109D01*
X695271Y759435D01*
X686269Y810490D01*
X675200Y826300D01*
Y840086D01*
X674615Y843398D01*
X668905Y851553D01*
X654586Y861579D01*
X650138Y867932D01*
Y872882D01*
G03X649188Y875176I-3244J0D01*
G01X932100Y264900D02*
Y272581D01*
X936268Y296217D01*
X933541Y311684D01*
X939861Y347523D01*
X923301Y441441D01*
X736985Y707528D01*
X725000Y775500D01*
X689200Y826627D01*
Y840500D01*
X688435Y844841D01*
X683170Y852360D01*
X667340Y863444D01*
X664036Y868163D01*
Y872882D01*
G02X664986Y875176I3244J0D01*
G01X928200Y264826D02*
Y272581D01*
X932575Y297397D01*
X930000Y312000D01*
X936126Y346740D01*
X919397Y441619D01*
X696502Y759945D01*
X687500Y811000D01*
X676500Y826710D01*
Y840200D01*
X675846Y843908D01*
X669839Y852487D01*
X655520Y862513D01*
X651438Y868343D01*
Y872882D01*
G02X652388Y875176I3244J0D01*
G01X930800Y265194D02*
Y272695D01*
X934947Y296217D01*
X932220Y311684D01*
X938540Y347525D01*
X922070Y440931D01*
X735754Y707018D01*
X723769Y774990D01*
X687900Y826217D01*
Y840386D01*
X687204Y844331D01*
X682236Y851426D01*
X666406Y862510D01*
X662736Y867753D01*
Y872882D01*
G03X661786Y875176I-3244J0D01*
G01X674742Y64292D02*
G02X675641Y68537I5680J1015D01*
G02X675718Y68648I4779J-3233D01*
G02X676069Y69093I4700J-3346D01*
G02X676601Y69448I910J-787D01*
G01X676611Y69451D01*
X688754Y72031D01*
X712193Y67053D01*
X727629Y69771D01*
X773461Y101867D01*
X800110Y107533D01*
X804927Y106509D01*
X809741Y105486D01*
X819027Y107119D01*
X822628Y106483D01*
X841862Y93017D01*
X851753Y91273D01*
X866911Y80660D01*
X879603Y78122D01*
X901990Y82067D01*
X903743Y83295D01*
X910374Y89926D01*
X919157Y96078D01*
X928395Y109267D01*
X930454Y111326D01*
G01X674742Y49331D02*
Y50262D01*
X674665Y50585D01*
X674861Y51761D01*
X675536Y53075D01*
X676773Y54312D01*
X695943Y60449D01*
X715582Y56989D01*
X740263Y61341D01*
X780863Y89773D01*
X783799Y90396D01*
X795177Y87978D01*
X813612Y91897D01*
X815063Y91589D01*
X815333Y91531D01*
X824729Y93528D01*
X827598Y92916D01*
X834983Y88485D01*
X842124Y81344D01*
X844489Y79810D01*
X856282Y77732D01*
X863439Y72722D01*
X879562Y69879D01*
X914136Y75978D01*
X920322Y80310D01*
X932629Y97881D01*
X937255Y102507D01*
Y111337D01*
G01X671789Y69803D02*
G03X674563Y69266I1502J324D01*
G02X674658Y69403I5858J-3960D01*
G02X675087Y69947I5760J-4101D01*
G02X676195Y70683I1890J-1643D01*
G02X676280Y70710I801J-2373D01*
G01X676288Y70712D01*
X676289D01*
X688754Y73361D01*
X712216Y68378D01*
X727119Y71002D01*
X772932Y103084D01*
X800110Y108863D01*
X809764Y106811D01*
X819027Y108440D01*
X823138Y107714D01*
X842372Y94248D01*
X852263Y92504D01*
X867434Y81882D01*
X879618Y79445D01*
X901480Y83298D01*
X902904Y84295D01*
X909104Y90495D01*
X909281Y90748D01*
X918223Y97012D01*
X927330Y110013D01*
Y110042D01*
X929534Y112246D01*
G01X671789Y54843D02*
G03X671953Y54447I560J0D01*
G01X672639Y53761D01*
G03X674383I872J873D01*
G01X674471Y53849D01*
X674472Y53851D01*
X676076Y55455D01*
X695852Y61786D01*
X715582Y58310D01*
X739753Y62572D01*
X780334Y90990D01*
X783799Y91726D01*
X795177Y89308D01*
X813612Y93227D01*
X815333Y92861D01*
X824729Y94858D01*
X828081Y94143D01*
X835790Y89518D01*
X842947Y82361D01*
X844975Y81045D01*
X856792Y78963D01*
X863949Y73953D01*
X879562Y71200D01*
X913626Y77209D01*
X916508Y79227D01*
Y79228D01*
X919388Y81244D01*
X931629Y98720D01*
X935955Y103046D01*
Y111337D01*
G01X872457Y164723D02*
X842504D01*
X842476Y164751D01*
X821073Y169300D01*
X798709Y183824D01*
X784488Y186847D01*
X770471Y196660D01*
X754807Y219034D01*
X751199Y239505D01*
Y240301D01*
X754788Y260659D01*
X748442Y296654D01*
X711820Y348955D01*
X698551Y358246D01*
X685096Y367667D01*
X681200Y373233D01*
Y377618D01*
X680100Y378718D01*
G01X683600D02*
X682500Y377618D01*
Y373643D01*
X686030Y368601D01*
X712566Y350020D01*
Y350021D01*
X712754Y349889D01*
X749673Y297164D01*
X756109Y260659D01*
X752499Y240187D01*
Y239619D01*
X756038Y219544D01*
X771405Y197594D01*
X785017Y188064D01*
X799215Y185046D01*
X821579Y170522D01*
X824357Y169932D01*
X825187Y170471D01*
X826801Y170128D01*
X827340Y169298D01*
X828954Y168955D01*
X829784Y169494D01*
X831398Y169151D01*
X831937Y168320D01*
X833551Y167977D01*
X834382Y168517D01*
X835996Y168173D01*
X836535Y167343D01*
X838149Y167000D01*
X838979Y167539D01*
X840593Y167196D01*
X841132Y166366D01*
X842746Y166023D01*
X872457D01*
G01X940000Y265100D02*
Y272581D01*
X944460Y297882D01*
X941590Y314161D01*
X947953Y350250D01*
X930088Y451588D01*
X778694Y667800D01*
X757500Y788000D01*
X738586Y815012D01*
X738585Y815013D01*
X738506Y815126D01*
X724146Y821296D01*
X711928Y833629D01*
X711860Y833726D01*
X689233Y866043D01*
Y872882D01*
G02X690183Y875176I3244J0D01*
G01X936000Y265000D02*
Y274315D01*
X940000Y297000D01*
X937339Y312089D01*
X943882Y349195D01*
X926692Y446681D01*
X775146Y663114D01*
X753452Y786148D01*
X740251Y805000D01*
X739614Y805912D01*
X738096Y808079D01*
X736554Y809027D01*
X736553Y809028D01*
X723187Y817243D01*
X707033Y832047D01*
X706983Y832118D01*
X692037Y853462D01*
X679761Y862058D01*
X676635Y866522D01*
Y872882D01*
G02X677585Y875176I3244J0D01*
G01X938700Y265100D02*
Y272695D01*
X943139Y297882D01*
X940269Y314161D01*
X946632Y350250D01*
X928857Y451078D01*
X777463Y667290D01*
X756269Y787490D01*
X737652Y814078D01*
X723400Y820200D01*
X710926Y832792D01*
X687933Y865632D01*
Y872882D01*
G03X686983Y875176I-3244J0D01*
G01X934700Y265000D02*
Y274429D01*
X938679Y297000D01*
X936018Y312089D01*
X942561Y349197D01*
X925461Y446171D01*
X773915Y662604D01*
X752221Y785638D01*
X737185Y807112D01*
X722400Y816200D01*
X706049Y831184D01*
X691103Y852528D01*
X678827Y861124D01*
X675335Y866111D01*
Y872882D01*
G03X674385Y875176I-3244J0D01*
G01X951700Y264700D02*
Y280680D01*
X945856Y313821D01*
X952500Y351500D01*
X934584Y453109D01*
X789026Y660986D01*
X763148Y807752D01*
X745700Y825200D01*
Y840000D01*
X745068Y843582D01*
X741856Y848170D01*
X736792Y851716D01*
X736770Y851707D01*
X736762Y851711D01*
X729732Y854618D01*
X721969Y855988D01*
X714100Y854600D01*
X706182Y855996D01*
X703286Y858024D01*
X701450Y860646D01*
Y866506D01*
G02X702400Y868800I3244J0D01*
G01X950400Y264700D02*
Y280566D01*
X944535Y313821D01*
X951179Y351500D01*
X933353Y452599D01*
X787795Y660476D01*
X761938Y807122D01*
X744400Y824661D01*
Y839886D01*
X743837Y843072D01*
X740922Y847236D01*
X736226Y850525D01*
X736222Y850527D01*
X729366Y853362D01*
X721969Y854667D01*
X714100Y853279D01*
X705672Y854765D01*
X702352Y857090D01*
X700150Y860235D01*
Y866174D01*
G03X699200Y868800I-4104J0D01*
G01X722955Y33095D02*
X723905Y34045D01*
Y35378D01*
G02X724448Y36687I1852J-1D01*
G01X725818Y38057D01*
G02X727127Y38600I1310J-1309D01*
G01X732542D01*
X733242Y39300D01*
X734892D01*
X735592Y38600D01*
X737242D01*
X737942Y39300D01*
X739592D01*
X740292Y38600D01*
X744015D01*
G03X745801Y39340I-1J2528D01*
G01X759790Y53329D01*
G02X762620Y54500I2829J-2831D01*
G01X773261D01*
G03X776164Y55703I-1J4107D01*
G01X779182Y58721D01*
G02X781546Y59700I2364J-2365D01*
G01X894593D01*
X895293Y60400D01*
X896943D01*
X897643Y59700D01*
X899293D01*
X899993Y60400D01*
X901643D01*
X902343Y59700D01*
X903993D01*
X904693Y60400D01*
X906343D01*
X907043Y59700D01*
X908693D01*
X909393Y60400D01*
X911043D01*
X911743Y59700D01*
X913393D01*
G03X917095Y61234I-1J5236D01*
G01X938587Y82727D01*
G03X939600Y85170I-2442J2444D01*
G01Y90727D01*
G02X940848Y93742I4263J1D01*
G01X941755Y94649D01*
G03X942437Y96293I-1644J1645D01*
G01Y100610D01*
G02X942980Y101919I1852J-1D01*
G01X943338Y102278D01*
G03X943500Y102667I-389J390D01*
G01Y142966D01*
G01X726155Y33095D02*
X725205Y34045D01*
Y35377D01*
G02X725367Y35767I552J-1D01*
G01X726738Y37138D01*
G02X727128Y37300I391J-390D01*
G01X744014D01*
G03X746721Y38420I1J3828D01*
G01X760710Y52409D01*
G02X762620Y53200I1910J-1911D01*
G01X773260D01*
G03X777084Y54783I1J5407D01*
G01X780102Y57801D01*
G02X781547Y58400I1446J-1445D01*
G01X913392D01*
G03X918015Y60314I1J6537D01*
G01X939507Y81807D01*
G03X940900Y85170I-3363J3363D01*
G01Y90727D01*
G02X941768Y92822I2962J0D01*
G01X942675Y93729D01*
G03X943737Y96293I-2564J2564D01*
G01Y100609D01*
G02X943899Y100999I552J-1D01*
G01X944258Y101358D01*
G03X944800Y102667I-1310J1309D01*
G01Y142932D01*
G01X726609Y49251D02*
X727559Y48301D01*
X729209D01*
X729909Y49001D01*
X731559D01*
X732259Y48301D01*
X733909D01*
X734609Y49001D01*
X736259D01*
X736959Y48301D01*
X738609D01*
X739309Y49001D01*
X740959D01*
X741659Y48301D01*
X746883D01*
G03X748792Y49092I-1J2702D01*
G01X758674Y58974D01*
G02X760912Y59900I2237J-2238D01*
G01X772151D01*
G03X774730Y60969I-1J3648D01*
G01X776682Y62921D01*
G02X781461Y64900I4779J-4781D01*
G01X895663D01*
X896363Y65600D01*
X898013D01*
X898713Y64900D01*
X900363D01*
X901063Y65600D01*
X902713D01*
X903413Y64900D01*
X905063D01*
X905763Y65600D01*
X907413D01*
X908113Y64900D01*
X909763D01*
X910463Y65600D01*
X912113D01*
X912813Y64900D01*
X914463D01*
G03X915556Y65353I0J1546D01*
G01X930072Y79870D01*
G03X931200Y82591I-2721J2722D01*
G01Y87414D01*
G02X932701Y91041I5129J1D01*
G01X936722Y95062D01*
G03X937600Y97179I-2116J2118D01*
G01Y98243D01*
G02X938445Y100285I2887J1D01*
G03X938800Y101140I-855J856D01*
G01Y113800D01*
G01X726609Y46051D02*
X727559Y47001D01*
X746882D01*
G03X749712Y48172I1J4002D01*
G01X759594Y58054D01*
G02X760912Y58600I1318J-1318D01*
G01X772150D01*
G03X775650Y60049I1J4948D01*
G01X777602Y62001D01*
G02X781462Y63600I3861J-3861D01*
G01X914464D01*
G03X916476Y64433I0J2847D01*
G01X930991Y78950D01*
X930992D01*
G03X932500Y82591I-3642J3641D01*
G01Y87414D01*
G02X933621Y90121I3829J0D01*
G01X937642Y94142D01*
G03X938900Y97179I-3037J3037D01*
G01Y98243D01*
G02X939365Y99365I1586J0D01*
G03X940100Y101140I-1776J1775D01*
G01Y113800D01*
G01X734277Y875176D02*
G03X733327Y872882I2294J-2294D01*
G01Y869946D01*
X737042Y864640D01*
X749997Y855569D01*
X758303Y843706D01*
X758780Y841000D01*
Y825743D01*
X767106Y813851D01*
X794022Y661189D01*
X938232Y455245D01*
X956220Y353224D01*
X949899Y317428D01*
X955800Y283963D01*
Y264500D01*
G01X731077Y875176D02*
G02X732027Y872882I-2294J-2294D01*
G01Y869535D01*
X736108Y863706D01*
X749063Y854635D01*
X757072Y843196D01*
X757480Y840886D01*
Y825333D01*
X765875Y813341D01*
X792791Y660679D01*
X937001Y454735D01*
X954899Y353224D01*
X948578Y317428D01*
X954500Y283849D01*
Y264500D01*
G01X959723D02*
Y284929D01*
X960557Y289661D01*
X955135Y320411D01*
X960315Y349786D01*
X940759Y460697D01*
X798213Y664275D01*
X770678Y820438D01*
X771200Y823400D01*
Y841100D01*
X770085Y847420D01*
X766532Y852493D01*
X748751Y864943D01*
X745926Y868977D01*
Y872882D01*
G02X746876Y875176I3244J0D01*
G01X958423Y264500D02*
Y285043D01*
X959236Y289661D01*
X953814Y320411D01*
X958994Y349788D01*
X939528Y460187D01*
X796982Y663765D01*
X769357Y820438D01*
X769900Y823514D01*
Y840986D01*
X768854Y846910D01*
X765598Y851559D01*
X747817Y864009D01*
X744626Y868567D01*
Y872882D01*
G03X743676Y875176I-3244J0D01*
G01X772073D02*
G03X771123Y872882I2294J-2294D01*
G01Y871453D01*
X773769Y867673D01*
X785956Y859140D01*
X795535Y845459D01*
X796357Y840800D01*
Y823530D01*
X794517Y820902D01*
X790940Y800609D01*
Y800095D01*
X817019Y652199D01*
X950623Y461394D01*
X970000Y351500D01*
X964622Y321000D01*
X970000Y290500D01*
X967597Y276872D01*
Y264497D01*
G01X759474Y875176D02*
G03X758524Y872882I2294J-2294D01*
G01Y872409D01*
X762495Y866737D01*
X775264Y857796D01*
X782330Y847705D01*
X783558Y840742D01*
Y825175D01*
X785000Y817000D01*
X783914Y810844D01*
X811904Y652107D01*
X945212Y461723D01*
X965000Y349500D01*
X959855Y320321D01*
X965189Y290072D01*
X963623Y281190D01*
Y264500D01*
G01X768873Y875176D02*
G02X769823Y872882I-2294J-2294D01*
G01Y871043D01*
X772835Y866739D01*
X785022Y858206D01*
X794304Y844949D01*
X795057Y840686D01*
Y823940D01*
X793286Y821412D01*
X789640Y800723D01*
Y800048D01*
X789630Y800038D01*
Y800037D01*
X815788Y651689D01*
X949392Y460884D01*
X968679Y351500D01*
X963301Y321000D01*
X968679Y290500D01*
X966297Y276986D01*
Y264497D01*
G01X756274Y875176D02*
G02X757224Y872882I-2294J-2294D01*
G01Y871998D01*
X761561Y865803D01*
X774330Y856862D01*
X781099Y847195D01*
X782258Y840628D01*
Y825061D01*
X783679Y817000D01*
X782593Y810844D01*
X810673Y651597D01*
X943981Y461213D01*
X963679Y349500D01*
X958534Y320321D01*
X963868Y290072D01*
X962323Y281304D01*
Y264500D01*
G01X784671Y875176D02*
G03X783721Y872882I2294J-2294D01*
G01Y871727D01*
X785727Y868862D01*
X803769Y856229D01*
X807171Y851371D01*
X809000Y841000D01*
Y823570D01*
X800589Y775867D01*
X821531Y657080D01*
X956662Y464087D01*
X976482Y351680D01*
X970186Y315974D01*
X974667Y290559D01*
X971497Y272581D01*
Y264697D01*
G01X781471Y875176D02*
G02X782421Y872882I-2294J-2294D01*
G01Y871317D01*
X784793Y867928D01*
X802835Y855295D01*
X805940Y850861D01*
X807700Y840886D01*
Y823684D01*
X799268Y775867D01*
X820300Y656570D01*
X955431Y463577D01*
X975161Y351680D01*
X968865Y315974D01*
X973346Y290559D01*
X970197Y272695D01*
Y264697D01*
G01X797270Y875176D02*
G03X796320Y872882I2294J-2294D01*
G01Y870314D01*
X799281Y866086D01*
X812992Y856485D01*
X818776Y848225D01*
X825179Y811909D01*
X812500Y740000D01*
X826320Y661623D01*
X959456Y471483D01*
X980461Y352359D01*
X974100Y316282D01*
X978603Y290746D01*
X975400Y272581D01*
Y264500D01*
G01X794070Y875176D02*
G02X795020Y872882I-2294J-2294D01*
G01Y869904D01*
X798347Y865152D01*
X812058Y855551D01*
X817545Y847715D01*
X823858Y811909D01*
X811179Y740000D01*
X825089Y661113D01*
X958225Y470973D01*
X979140Y352359D01*
X972779Y316282D01*
X977282Y290746D01*
X974100Y272695D01*
Y264500D01*
G01X847663Y875176D02*
G03X846713Y872882I2294J-2294D01*
G01Y867105D01*
X845603Y860811D01*
X847816Y848262D01*
X846500Y840800D01*
Y824000D01*
X845217Y816724D01*
X840417Y809869D01*
X827566Y736983D01*
X839124Y671432D01*
X970094Y484389D01*
X994694Y344876D01*
X989488Y315351D01*
X994107Y289157D01*
X991184Y272581D01*
Y264584D01*
G01X835065Y875176D02*
G03X834115Y872882I2294J-2294D01*
G01Y864682D01*
X835852Y854833D01*
X831875Y832232D01*
Y831718D01*
X835000Y814000D01*
X821873Y739554D01*
X834451Y668223D01*
X965944Y480430D01*
X990000Y344000D01*
X985195Y316752D01*
X990000Y289500D01*
X987200Y273620D01*
Y264500D01*
G01X979400Y264600D02*
Y272581D01*
X982462Y289947D01*
X977686Y317033D01*
X983976Y352705D01*
X962064Y476974D01*
X829628Y666114D01*
X816531Y740388D01*
X829091Y811621D01*
X822229Y850534D01*
X809370Y868897D01*
G02X808918Y870331I2048J1434D01*
G01Y872882D01*
G02X809868Y875176I3244J0D01*
G01X989884Y264584D02*
Y272695D01*
X992786Y289157D01*
X988167Y315351D01*
X993373Y344876D01*
X968863Y483879D01*
X837893Y670922D01*
X826245Y736983D01*
X839186Y810379D01*
X843986Y817234D01*
X845200Y824114D01*
Y840914D01*
X846495Y848262D01*
X844282Y860811D01*
X845413Y867223D01*
Y872882D01*
G03X844463Y875176I-3244J0D01*
G01X831865D02*
G02X832815Y872882I-2294J-2294D01*
G01Y864565D01*
X834531Y854833D01*
X830575Y832346D01*
Y831671D01*
X830565Y831661D01*
Y831660D01*
X833679Y814000D01*
X820552Y739554D01*
X833220Y667713D01*
X964713Y479920D01*
X988679Y344000D01*
X983874Y316752D01*
X988679Y289500D01*
X985900Y273734D01*
Y264500D01*
G01X978100Y264600D02*
Y272695D01*
X981141Y289947D01*
X976365Y317033D01*
X982655Y352705D01*
X960833Y476464D01*
X828397Y665604D01*
X815210Y740388D01*
X827770Y811621D01*
X820998Y850024D01*
X808305Y868150D01*
G02X807618Y870329I3113J2179D01*
G01Y872882D01*
G03X806668Y875176I-3244J0D01*
G01X1061200Y20888D02*
X1060250Y21838D01*
X1054027D01*
X1052407Y23786D01*
X1046588Y35639D01*
X1039593Y40537D01*
X1032595Y45436D01*
X989815Y52979D01*
X987850Y53325D01*
X986512Y54262D01*
X974330Y66444D01*
X967599Y71217D01*
X953112Y81490D01*
X950125Y84478D01*
Y88433D01*
X946287Y94658D01*
Y142267D01*
G01X1061200Y24088D02*
X1060250Y23138D01*
X1054637D01*
X1053507Y24497D01*
X1053506Y24498D01*
X1047608Y36512D01*
X1033105Y46667D01*
X990040Y54259D01*
X988360Y54556D01*
X987351Y55262D01*
X975172Y67441D01*
X971716Y69892D01*
X961622Y77050D01*
X961456Y78026D01*
X960110Y78981D01*
X959134Y78815D01*
X957788Y79769D01*
X957622Y80745D01*
X956276Y81700D01*
X955300Y81534D01*
X953954Y82488D01*
X951425Y85017D01*
Y88802D01*
X947587Y95027D01*
Y142267D01*
G01X1065700Y32888D02*
X1064771Y33817D01*
X1059574D01*
X1057243Y36148D01*
Y41162D01*
X1056046Y42359D01*
X1044396Y45513D01*
X1036583Y53326D01*
X1017000Y56779D01*
X1015062Y56437D01*
X1011893Y55878D01*
X1006697Y54961D01*
X988202Y58223D01*
X951950Y94476D01*
Y111629D01*
X950549Y113030D01*
Y114119D01*
G01X1065700Y36088D02*
X1064729Y35117D01*
X1060113D01*
X1058543Y36687D01*
Y41701D01*
X1058162Y42082D01*
X1058163D01*
X1056721Y43524D01*
X1054144Y44221D01*
X1053652Y45080D01*
X1052059Y45511D01*
X1051200Y45019D01*
X1049608Y45450D01*
X1049115Y46308D01*
X1047522Y46740D01*
X1046664Y46247D01*
X1045071Y46678D01*
X1037213Y54536D01*
X1017000Y58100D01*
X1015319Y57803D01*
X1014836Y57718D01*
X1011667Y57159D01*
X1006697Y56282D01*
X988832Y59433D01*
X953250Y95015D01*
Y112168D01*
X951849Y113569D01*
Y114119D01*
G01X1138324Y49331D02*
G02X1136162Y51762I-1010J1279D01*
G01X1139753Y55353D01*
G02X1139994Y55584I5914J-5929D01*
G01X1140265Y55821D01*
X1142463Y57170D01*
X1142464Y57169D01*
X1144955Y58199D01*
X1146722D01*
X1149226Y57161D01*
X1154245Y52142D01*
X1155744Y48525D01*
Y34361D01*
X1152010Y29029D01*
X1145400Y24400D01*
X1136830Y22889D01*
X1102548Y28933D01*
X1097353Y32572D01*
X1096999Y32820D01*
X1096409Y33232D01*
X1087559Y34793D01*
X1080733Y33588D01*
X1056984Y50449D01*
X1045531Y52469D01*
X1039937Y58063D01*
X1019660Y62799D01*
X1007089Y60284D01*
X992029Y62814D01*
X957900Y96942D01*
Y104400D01*
X959575Y106075D01*
Y109698D01*
X957897Y111376D01*
G01X1138324Y64292D02*
G03X1135465Y64647I-1568J-936D01*
G01X1129373Y58556D01*
X1119534Y56820D01*
X1117500Y57179D01*
X1113903Y56545D01*
X1112236Y55378D01*
X1111737Y54666D01*
X1111546Y53580D01*
X1111879Y51693D01*
X1116540Y45036D01*
X1116901Y42989D01*
X1116380Y40034D01*
X1115254Y38425D01*
X1110562Y35140D01*
X1106215Y34374D01*
X1101092Y35277D01*
X1097924Y37496D01*
X1094686Y42121D01*
X1094635Y42406D01*
X1094636D01*
X1092338Y55437D01*
X1088946Y60280D01*
X1081017Y65832D01*
X1076271Y66670D01*
X1058261Y63068D01*
X1047231Y65274D01*
X1034731Y62774D01*
X1022231Y65274D01*
X1009731Y62774D01*
X994692Y65300D01*
X961250Y98742D01*
Y111484D01*
G01X1147183Y64292D02*
Y72000D01*
G03X1146464Y73736I-2455J0D01*
G01X1144800Y75400D01*
G03X1144379Y75752I-2174J-2172D01*
G03X1142627Y76300I-1752J-2525D01*
G01X1134770D01*
X1126213Y74791D01*
X1110904Y64071D01*
X1105831Y63177D01*
X1100600Y64100D01*
X1093841Y68833D01*
X1075205Y72119D01*
X1061108Y69300D01*
X1048608Y71800D01*
X1036108Y69300D01*
X1023608Y71800D01*
X1011088Y69296D01*
X996695Y71714D01*
X965500Y102908D01*
Y114838D01*
G03X964960Y116142I-1844J0D01*
G01X1103300Y73900D02*
X1102796Y73395D01*
G02X1101230Y72747I-1565J1566D01*
G01X1098695D01*
X1077564Y76473D01*
X1063423Y73645D01*
X1048642Y76601D01*
X1037639Y74400D01*
X1025139Y76900D01*
X1018635Y75599D01*
X1012619Y74396D01*
X998226Y76814D01*
X968700Y106339D01*
Y119603D01*
G02X968897Y120079I673J0D01*
G01X1112700Y80700D02*
G03X1111384Y83164I-2965J0D01*
G01X1111096Y83423D01*
X1106947D01*
X1100121Y79994D01*
X1095571Y79192D01*
X1091209Y78423D01*
Y78422D01*
X1090984Y78383D01*
X1072805Y81589D01*
X1060495Y79127D01*
X1051262Y80974D01*
X1038762Y78474D01*
X1026262Y80974D01*
X1020011Y79724D01*
X1013762Y78474D01*
X998723Y81000D01*
X973536Y106187D01*
Y114345D01*
G03X972834Y116142I-2651J0D01*
G01X1135372Y54843D02*
X1136375D01*
G03X1136919Y54903I2J2482D01*
G03X1138130Y55570I-545J2422D01*
G01X1139018Y56458D01*
X1139490Y56872D01*
X1141844Y58316D01*
X1141865Y58330D01*
X1144697Y59499D01*
X1146981D01*
X1149963Y58263D01*
X1155348Y52879D01*
X1157044Y48784D01*
Y33951D01*
X1152944Y28095D01*
X1145910Y23169D01*
X1136830Y21568D01*
X1102038Y27702D01*
X1101801Y27868D01*
X1101802D01*
X1098070Y30482D01*
X1096607Y31507D01*
X1095900Y32001D01*
X1087559Y33472D01*
X1080424Y32213D01*
X1056470Y49219D01*
X1044901Y51259D01*
X1039280Y56881D01*
X1019639Y61468D01*
X1007109Y58962D01*
X991403Y61600D01*
X956600Y96403D01*
Y104939D01*
X958275Y106614D01*
Y109159D01*
X956967Y110467D01*
G01X1135372Y69803D02*
G02X1135933Y66955I-675J-1612D01*
G01X1128743Y59766D01*
X1119534Y58141D01*
X1117500Y58500D01*
X1113393Y57776D01*
X1111303Y56312D01*
X1110506Y55176D01*
X1110225Y53580D01*
X1110648Y51182D01*
X1115309Y44526D01*
X1115580Y42989D01*
X1115149Y40544D01*
X1114320Y39359D01*
X1110052Y36371D01*
X1106215Y35695D01*
X1101602Y36508D01*
X1098858Y38429D01*
X1095917Y42631D01*
X1093569Y55947D01*
X1089880Y61214D01*
X1081527Y67063D01*
X1076256Y67993D01*
X1058261Y64394D01*
X1047231Y66600D01*
X1034731Y64100D01*
X1022231Y66600D01*
X1009711Y64096D01*
X995318Y66514D01*
X962550Y99281D01*
Y111484D01*
G01X1144230Y69803D02*
G03X1145881Y71762I-337J1959D01*
G01Y72000D01*
G03X1145544Y72815I-1154J0D01*
G01X1145545Y72816D01*
X1143888Y74473D01*
G03X1143637Y74683I-1303J-1302D01*
G03X1142627Y75000I-1012J-1455D01*
G01X1134884D01*
X1126723Y73560D01*
X1111414Y62840D01*
X1105831Y61856D01*
X1105604Y61896D01*
X1105605D01*
X1100090Y62869D01*
X1093331Y67602D01*
X1075220Y70796D01*
X1061108Y67974D01*
X1048608Y70474D01*
X1036108Y67974D01*
X1023608Y70474D01*
X1011108Y67974D01*
X996069Y70500D01*
X964200Y102369D01*
Y113000D01*
G03X964155Y113357I-1449J-1D01*
G03X963776Y114025I-1405J-356D01*
G01X963550Y114250D01*
G02X963200Y115095I845J845D01*
G01Y116230D01*
X964678Y119797D01*
X964960Y120079D01*
G01X1103349Y70700D02*
G03X1101553Y71444I-1796J-1796D01*
G01X1101230D01*
Y71447D01*
X1098581D01*
X1077579Y75150D01*
X1063423Y72319D01*
X1048642Y75275D01*
X1037639Y73074D01*
X1025139Y75574D01*
X1012639Y73074D01*
X997600Y75600D01*
X967400Y105800D01*
Y118400D01*
X967000Y118800D01*
Y120900D01*
G02X967862Y122981I2943J0D01*
G01X968897Y124016D01*
G01X972834Y120079D02*
G02X974836Y114345I-7210J-5734D01*
G01Y106726D01*
X999349Y82214D01*
X1013742Y79796D01*
X1026262Y82300D01*
X1038762Y79800D01*
X1051262Y82300D01*
X1060495Y80453D01*
X1072790Y82912D01*
X1090984Y79704D01*
X1099707Y81242D01*
X1106638Y84723D01*
X1111596D01*
X1112254Y84130D01*
G03X1114842Y83078I2588J2657D01*
G01X1181631Y64292D02*
G03X1179570Y66138I-1221J710D01*
G03X1178849Y65344I1628J-2203D01*
G03X1178652Y64854I1436J-862D01*
G01X1178651D01*
G02X1175806Y60752I-6559J1512D01*
G01X1174453Y59855D01*
X1171516Y59222D01*
X1160177Y64312D01*
X1158233Y66687D01*
X1158028Y67851D01*
X1157642Y70038D01*
X1158626Y75619D01*
X1157392Y82612D01*
X1155444Y85394D01*
X1151943Y87847D01*
X1141320Y89720D01*
X1131000Y87900D01*
X1119697Y89893D01*
X1090295Y84709D01*
X1078546Y86780D01*
X1068916Y85082D01*
X1050669Y88300D01*
X1038039Y85774D01*
X1025541Y88273D01*
X1013057Y85777D01*
X997911Y88388D01*
X976418Y109881D01*
Y116244D01*
G02X976530Y117607I8313J3D01*
G02X976810Y118768I8200J-1363D01*
G03X976771Y120079I-1883J600D01*
G01X1190490Y64292D02*
X1190017Y64186D01*
G02X1188543Y65280I-18J1516D01*
G02X1189319Y67300I1720J498D01*
G03X1189836Y67477I-556J2468D01*
G03X1190616Y68045I-1072J2291D01*
G01X1190615D01*
G03X1190796Y73027I-2785J2595D01*
G01X1190304Y73639D01*
X1189636Y74472D01*
X1187145Y75721D01*
X1185236Y75977D01*
X1183277Y76240D01*
X1178376Y74852D01*
X1169564Y77133D01*
X1164980Y80470D01*
X1163523Y88729D01*
X1155946Y99551D01*
X1151425Y102717D01*
X1145279Y103800D01*
X1124197D01*
X1118388Y101631D01*
X1093129Y97177D01*
X1079653Y99554D01*
X1040251Y91750D01*
X1027753Y94248D01*
X1015249Y91750D01*
X998624Y94616D01*
X983216Y110024D01*
X981566Y111673D01*
G02X980326Y114418I3573J3266D01*
G02X980708Y116142I2742J297D01*
G01X1190490Y49331D02*
G02X1189222Y52178I-88J1667D01*
G01X1191512Y54469D01*
X1196780Y59738D01*
X1196781Y59740D01*
X1198100Y67276D01*
Y81712D01*
G03X1197648Y83146I-2501J0D01*
G01X1195080Y86814D01*
X1191640Y89223D01*
X1183686Y90625D01*
X1176353Y89332D01*
X1172943Y89933D01*
X1169941Y92035D01*
X1166604Y96801D01*
X1165015Y105811D01*
X1162921Y108801D01*
X1159363Y111293D01*
X1152263Y112545D01*
X1141230Y110600D01*
X1132672Y112109D01*
X1043725Y96423D01*
X1029252Y98976D01*
X1016996Y96525D01*
X1002760Y98817D01*
X986500Y115077D01*
Y117439D01*
X985200Y118739D01*
G02X984645Y120079I1340J1340D01*
G01X1178679Y69803D02*
G02X1177735Y66015I-6643J-356D01*
G03X1177384Y65146I2549J-1535D01*
G02X1175088Y61836I-5292J1220D01*
G01X1174514Y61456D01*
X1173939Y61075D01*
X1171659Y60583D01*
X1160989Y65373D01*
X1159455Y67248D01*
X1159309Y68077D01*
X1158963Y70038D01*
X1159415Y72603D01*
X1159947Y75619D01*
X1158623Y83122D01*
X1156509Y86140D01*
Y86141D01*
X1156378Y86327D01*
X1152453Y89078D01*
X1141320Y91041D01*
X1131000Y89221D01*
X1119697Y91214D01*
X1090295Y86030D01*
X1078546Y88101D01*
X1068916Y86403D01*
X1050654Y89623D01*
X1038039Y87100D01*
X1025541Y89599D01*
X1013039Y87100D01*
X998539Y89600D01*
X977718Y110420D01*
Y116244D01*
G02X977813Y117394I7012J0D01*
G02X978049Y118373I6917J-1150D01*
G03X978399Y120627I-3986J1773D01*
G03X976771Y124016I-5642J-625D01*
G01X1187537Y69803D02*
G03X1189285Y68656I1228J-34D01*
G03X1189664Y68932I-521J1113D01*
G03X1189783Y72212I-1834J1709D01*
G01X1188799Y73436D01*
X1186756Y74461D01*
X1184219Y74800D01*
X1183365Y74913D01*
X1181181Y74295D01*
X1178391Y73505D01*
X1168999Y75936D01*
X1163790Y79727D01*
X1162292Y88219D01*
X1155012Y98617D01*
X1152965Y100051D01*
X1152964D01*
X1150915Y101486D01*
X1145165Y102500D01*
X1124432D01*
X1118731Y100371D01*
X1093129Y95856D01*
X1079667Y98231D01*
X1040249Y90424D01*
X1027753Y92922D01*
X1015267Y90427D01*
X997996Y93404D01*
X980627Y110773D01*
G02X979033Y114278I4512J4167D01*
G02X978997Y114940I6105J664D01*
G01Y115865D01*
G02X980708Y120079I6045J0D01*
G01X1187537Y54843D02*
G03X1190592Y55389I1136J2465D01*
G01X1195570Y60367D01*
X1196800Y67395D01*
Y81712D01*
G03X1196583Y82400I-1201J0D01*
G01X1194146Y85880D01*
X1191130Y87992D01*
X1183686Y89304D01*
X1176353Y88011D01*
X1172433Y88702D01*
X1169007Y91101D01*
X1165373Y96291D01*
X1163784Y105301D01*
X1161987Y107867D01*
X1158853Y110062D01*
X1152263Y111224D01*
X1141215Y109277D01*
X1141005Y109319D01*
X1132672Y110788D01*
X1043725Y95102D01*
X1029267Y97653D01*
X1017021Y95204D01*
X1002138Y97600D01*
X985200Y114538D01*
Y116900D01*
X982800Y119300D01*
Y121200D01*
G02X983487Y122857I2344J-1D01*
G01X983514Y122885D01*
X984645Y124016D01*
G01X1233797Y64292D02*
Y67499D01*
G02X1233892Y67930I1021J1D01*
G02X1233894Y67935I948J-376D01*
G02X1233919Y67984I922J-439D01*
G02X1233935Y68013I902J-479D01*
G02X1234006Y68119I882J-514D01*
G02X1234077Y68202I811J-621D01*
G01X1234054Y68221D01*
G03X1234432Y68828I-1623J1432D01*
G01X1234569Y69160D01*
G03X1234793Y70291I-2739J1130D01*
G01Y72471D01*
G03X1233681Y75159I-3802J1D01*
G03X1230441Y76500I-3239J-3240D01*
G01X1214308D01*
X1212022Y78480D01*
X1210695Y80375D01*
X1210021Y84200D01*
X1210387Y86276D01*
X1209372Y92036D01*
X1206561Y96051D01*
X1206262Y97748D01*
X1207883Y106944D01*
X1206831Y112910D01*
X1203561Y117579D01*
X1199315Y120552D01*
X1189506Y122282D01*
X1174550Y119645D01*
X1169011Y120621D01*
X1165179Y123304D01*
X1157917Y124584D01*
X1139149Y121276D01*
X1131441Y122633D01*
X1131205Y122669D01*
X1119879Y120733D01*
X1119877Y120734D01*
Y120733D01*
X1106573Y124671D01*
X1095276Y131635D01*
X1052042Y139253D01*
X1039271Y136700D01*
X1020540D01*
X1019327Y137913D01*
G01X1022407Y126093D02*
X1035066D01*
X1038815Y126843D01*
X1083326Y119789D01*
X1091549Y118486D01*
X1099773Y117184D01*
X1120199Y113946D01*
X1131729Y116252D01*
X1141415Y114703D01*
X1153450Y117110D01*
X1159471Y115905D01*
X1165231Y114753D01*
Y114754D01*
X1165500Y114700D01*
X1168635Y112505D01*
X1171500Y112000D01*
X1184059Y114214D01*
X1193469Y112555D01*
X1196563Y110389D01*
X1198306Y107899D01*
X1198876Y104665D01*
X1197813Y98632D01*
X1199452Y89341D01*
X1202500Y84986D01*
Y69900D01*
X1211200Y61200D01*
X1222700D01*
X1225935Y57965D01*
Y54394D01*
G02X1225554Y52908I-3095J2D01*
G02X1225276Y52486I-2714J1486D01*
G03X1225009Y51976I1247J-977D01*
G03X1225000Y51948I1504J-499D01*
G03X1224995Y51929I1529J-413D01*
G03X1224939Y51509I1528J-417D01*
G01Y49331D01*
G01Y64292D02*
G02X1225681Y68004I5836J764D01*
G03X1226122Y69519I-2856J1653D01*
G03X1225748Y71855I-5899J254D01*
G03X1222772Y73910I-2975J-1126D01*
G01X1220897D01*
G03X1219721Y73648I0J-2771D01*
G03X1218937Y73098I1178J-2513D01*
G01X1218820Y72980D01*
X1218520Y72680D01*
X1218519D01*
X1218422Y72583D01*
G03X1218325Y72480I1666J-1666D01*
G03X1217845Y71646I1759J-1567D01*
G01X1217706Y71221D01*
G02X1217425Y70764I-1098J360D01*
G01X1214000Y67339D01*
X1212061D01*
X1206500Y72900D01*
Y86671D01*
X1203410Y91086D01*
X1202182Y98050D01*
X1203435Y105159D01*
X1202459Y110703D01*
X1200697Y113218D01*
X1198879Y115015D01*
X1197044Y116299D01*
X1185783Y118284D01*
X1174309Y116262D01*
X1166445Y117648D01*
X1162661Y120295D01*
X1160997Y120589D01*
X1160111Y120745D01*
X1157620Y121184D01*
X1139830Y118049D01*
X1131543Y119463D01*
X1119559Y117349D01*
X1103495Y120180D01*
X1102444Y120916D01*
X1097892Y124103D01*
X1047365Y133013D01*
X1035272Y130594D01*
X1022776D01*
G01X1230844Y69803D02*
X1231445Y69202D01*
G03X1232387Y68812I942J942D01*
G01X1232544D01*
G03X1232761Y68855I0J569D01*
G03X1233079Y69082I-330J799D01*
G03X1233230Y69324I-648J572D01*
G01X1233367Y69656D01*
G03X1233493Y70291I-1537J635D01*
G01Y72471D01*
G03X1232761Y74239I-2501J0D01*
G03X1230441Y75200I-2320J-2320D01*
G01X1213823D01*
X1211049Y77602D01*
X1209464Y79865D01*
X1208700Y84200D01*
X1208855Y85076D01*
X1209066Y86276D01*
X1208141Y91526D01*
X1205330Y95541D01*
X1204941Y97748D01*
X1206562Y106944D01*
X1205600Y112400D01*
X1202627Y116645D01*
X1198805Y119321D01*
X1189506Y120961D01*
X1174550Y118324D01*
X1168501Y119390D01*
X1164668Y122074D01*
X1164667D01*
X1157917Y123263D01*
X1139150Y119955D01*
X1131229Y121350D01*
X1131216Y121352D01*
X1119800Y119400D01*
X1106038Y123473D01*
X1094805Y130397D01*
X1052057Y137930D01*
X1039400Y135400D01*
X1020000D01*
X1018407Y136993D01*
G01X1230844Y54843D02*
X1231022Y54414D01*
G03X1231442Y53902I1055J437D01*
G03X1231908Y53709I466J466D01*
G01X1232346D01*
G03X1232959Y53963I0J867D01*
G01X1233158Y54162D01*
G03X1233492Y54968I-806J806D01*
G03X1233493Y55001I-1216J53D01*
G01Y57770D01*
G02X1234499Y60199I3437J-1D01*
G01X1239134Y64835D01*
G03X1239700Y66200I-1365J1366D01*
G01Y93700D01*
X1241229Y101344D01*
X1240196Y106922D01*
X1238951Y109346D01*
X1234742Y112294D01*
X1229754Y113173D01*
X1220398Y119725D01*
X1185636Y125854D01*
X1173220Y123665D01*
X1157202Y126489D01*
X1147762Y124844D01*
X1145458Y124442D01*
X1142002Y123841D01*
X1141879Y123819D01*
X1141075Y123679D01*
X1139179Y123349D01*
X1138323Y123200D01*
X1130578Y124564D01*
X1122415Y123123D01*
X1112138Y125263D01*
X1106030Y129540D01*
X1099923Y133815D01*
X1049957Y143809D01*
X1037481Y140043D01*
X1022918D01*
X1021517Y141444D01*
X1018550D01*
G01X1221986Y54843D02*
G03X1221693Y54136I707J-707D01*
G01Y53454D01*
G03X1222547Y52600I854J0D01*
G01X1222993D01*
G03X1223968Y53004I0J1379D01*
G01X1224123Y53159D01*
G03X1224635Y54395I-1236J1236D01*
G01Y57426D01*
X1222161Y59900D01*
X1210661D01*
X1201200Y69361D01*
Y84576D01*
X1198221Y88831D01*
X1196492Y98632D01*
X1197555Y104665D01*
X1197075Y107389D01*
X1195629Y109455D01*
X1192959Y111324D01*
X1184059Y112893D01*
X1171500Y110679D01*
X1168125Y111274D01*
X1164977Y113478D01*
X1159216Y114630D01*
X1153450Y115784D01*
X1141441Y113382D01*
X1131755Y114931D01*
X1120226Y112625D01*
X1099569Y115899D01*
X1083122Y118504D01*
X1038842Y125522D01*
X1035197Y124793D01*
X1022407D01*
G01X1022776Y129294D02*
X1035401D01*
X1047380Y131690D01*
X1097382Y122872D01*
X1099014Y121730D01*
X1100552Y120653D01*
X1100648Y120586D01*
X1102985Y118949D01*
X1119559Y116028D01*
X1131547Y118143D01*
X1139834Y116729D01*
X1157620Y119863D01*
X1162151Y119064D01*
X1163329Y118239D01*
X1165933Y116418D01*
X1174310Y114941D01*
X1185783Y116963D01*
X1189804Y116253D01*
X1191095Y116026D01*
X1193815Y115547D01*
X1196534Y115068D01*
X1198043Y114013D01*
X1199699Y112375D01*
X1201228Y110193D01*
X1201320Y109669D01*
X1202114Y105159D01*
X1200861Y98050D01*
X1202179Y90576D01*
X1205200Y86261D01*
Y72361D01*
X1211522Y66039D01*
X1214539D01*
X1218300Y69800D01*
X1218345Y69844D01*
G03X1218942Y70816I-1737J1736D01*
G01X1219032Y71091D01*
X1219081Y71241D01*
G02X1219297Y71616I1003J-328D01*
G02X1219342Y71663I784J-706D01*
G01X1219439Y71760D01*
X1219440D01*
X1219742Y72062D01*
X1219858Y72180D01*
G02X1220273Y72470I1040J-1046D01*
G02X1220898Y72610I626J-1331D01*
G01X1222772D01*
G02X1224531Y71395I0J-1881D01*
G02X1224823Y69574I-4308J-1625D01*
G02X1224555Y68656I-1998J85D01*
G02X1224126Y68140I-1730J1002D01*
G02X1221986Y69803I-900J1051D01*
G01X1233797Y49331D02*
Y52539D01*
G02X1234096Y53261I1021J0D01*
G02X1234109Y53274I760J-747D01*
G03X1234792Y54923I-1833J1725D01*
G03Y54940I-2516J9D01*
G03X1234793Y54992I-2516J74D01*
G01Y57769D01*
G02X1235419Y59280I2137J0D01*
G01X1240054Y63915D01*
G03X1241000Y66199I-2285J2284D01*
G01Y93571D01*
X1242553Y101335D01*
X1241440Y107346D01*
X1239961Y110227D01*
X1235252Y113525D01*
X1230264Y114404D01*
X1220908Y120956D01*
X1185636Y127175D01*
X1173220Y124986D01*
X1165208Y126399D01*
X1157203Y127809D01*
X1155629Y127535D01*
X1147539Y126125D01*
X1138324Y124520D01*
X1130578Y125885D01*
X1122435Y124447D01*
X1112665Y126482D01*
X1100446Y135037D01*
X1049893Y145148D01*
X1043344Y143171D01*
X1037289Y141343D01*
X1023457D01*
X1022056Y142744D01*
X1018600D01*
G01X1268246Y49331D02*
G02X1268951Y53093I7562J530D01*
G03X1269242Y54394I-2758J1300D01*
G01Y55800D01*
G03X1266142Y58900I-3100J0D01*
G01X1257363D01*
X1250397Y62234D01*
X1246988Y67103D01*
X1246262Y71216D01*
Y93525D01*
X1248239Y104739D01*
X1247306Y110026D01*
X1226337Y124709D01*
X1219530Y126156D01*
X1207280Y144722D01*
X1185763Y159160D01*
X1173933Y161674D01*
X1132145Y153144D01*
X1117239Y156126D01*
X1092239Y151126D01*
X1067239Y156126D01*
X1034901Y146301D01*
X1022300D01*
G01X1021268Y150268D02*
X1034524D01*
X1065539Y160526D01*
X1090539Y155526D01*
X1115539Y160526D01*
X1131818Y157270D01*
X1172713Y165638D01*
X1188321Y162321D01*
X1202780Y152931D01*
X1220219Y149855D01*
X1220225Y149849D01*
X1220231D01*
X1220780Y149822D01*
X1220781D01*
X1235126Y152871D01*
X1239389Y151965D01*
X1245228Y148173D01*
X1250213Y140497D01*
X1250959Y136988D01*
X1249672Y130935D01*
X1250436Y126591D01*
X1252665Y123408D01*
X1253410Y119181D01*
X1253324Y118747D01*
X1253019Y117226D01*
X1252701Y115638D01*
Y111092D01*
X1253744Y105882D01*
X1251700Y95666D01*
Y80174D01*
G03X1257212Y74662I5512J0D01*
G01X1265328D01*
G02X1269358Y70632I0J-4030D01*
G01Y69649D01*
G02X1269106Y68354I-3435J-4D01*
G03X1268246Y64292I10945J-4439D01*
G01X1277104D02*
Y67499D01*
G02X1277403Y68221I1021J0D01*
G02X1277416Y68234I760J-747D01*
G03X1278099Y69883I-1833J1725D01*
G03Y69900I-2516J8D01*
G03X1278100Y69952I-2516J74D01*
G01Y72265D01*
X1278849Y73335D01*
X1290191Y81652D01*
X1293420Y96848D01*
X1289721Y114639D01*
X1287785Y117613D01*
X1283873Y120155D01*
X1272276Y122619D01*
X1270608Y125187D01*
X1265798Y147812D01*
X1263025Y151973D01*
X1256052Y156500D01*
X1178867Y170111D01*
X1155177Y165933D01*
X1131490Y161756D01*
X1113139Y165426D01*
X1088068Y160412D01*
X1063084Y165409D01*
X1030851Y155651D01*
X1023750D01*
G01X1277104Y49331D02*
Y52539D01*
G02X1277403Y53261I1021J0D01*
G02X1277416Y53274I760J-747D01*
G03X1278099Y54923I-1833J1725D01*
G03Y54940I-2516J9D01*
G03X1278100Y54992I-2516J74D01*
G01Y58861D01*
X1292227Y72987D01*
X1298062Y100439D01*
X1296259Y108930D01*
X1301985Y135883D01*
X1300567Y142559D01*
X1280939Y155308D01*
X1183220Y176078D01*
X1158060Y171246D01*
X1133159Y166465D01*
X1133160Y166462D01*
X1112912Y171953D01*
X1109116Y171249D01*
X1086655Y167088D01*
X1062548Y170872D01*
X1030588Y160300D01*
X1020800D01*
G01X1022340Y168660D02*
X1025267D01*
X1071228Y176763D01*
X1110934Y204566D01*
X1149685Y259730D01*
X1234758Y708755D01*
X1302501Y805500D01*
X1313387Y813122D01*
X1317800Y813900D01*
X1328201Y821182D01*
X1330178Y824005D01*
Y841322D01*
X1332284Y853268D01*
X1342776Y868273D01*
Y873200D01*
G02X1343501Y874952I2477J1D01*
G01X1343726Y875176D01*
G01X1331128D02*
X1330903Y874952D01*
G03X1330178Y873200I1752J-1751D01*
G01Y862191D01*
X1318000Y844800D01*
X1317600Y842531D01*
Y825278D01*
X1315080Y822758D01*
X1297796Y810656D01*
X1226972Y709537D01*
X1146856Y261190D01*
X1112003Y211416D01*
X1111782Y211194D01*
X1070801Y180587D01*
X1025268Y172560D01*
X1023022D01*
G01X1318529Y875176D02*
X1318304Y874952D01*
G03X1317579Y873200I1752J-1751D01*
G01Y863281D01*
X1316893Y859389D01*
X1306192Y844106D01*
X1303115Y826648D01*
X1222683Y711779D01*
X1143222Y261322D01*
X1109716Y213469D01*
X1067563Y183953D01*
X1025267Y176497D01*
X1022500D01*
G01X1265293Y54843D02*
X1265074Y54347D01*
G03X1267592Y53236I1259J-555D01*
G01X1267774Y53648D01*
G03X1267941Y54394I-1581J746D01*
G01X1267942Y54393D01*
Y55800D01*
G03X1266142Y57600I-1800J0D01*
G01X1257065D01*
X1249527Y61208D01*
X1245757Y66593D01*
X1244962Y71102D01*
Y93639D01*
X1246918Y104739D01*
X1246518Y107005D01*
Y107006D01*
X1246119Y109270D01*
X1225808Y123492D01*
X1218738Y124995D01*
X1206338Y143787D01*
X1185247Y157940D01*
X1173928Y160346D01*
X1163481Y158213D01*
Y158212D01*
X1153037Y156081D01*
Y156080D01*
X1132148Y151817D01*
X1117239Y154800D01*
X1092239Y149800D01*
X1067306Y154786D01*
X1035095Y145001D01*
X1022300D01*
G01X1265293Y69803D02*
X1265168Y69468D01*
G03X1265980Y67684I1298J-486D01*
G01X1265982Y67683D01*
G03X1267766Y68496I486J1298D01*
G01Y68497D01*
G02X1267901Y68843I12281J-4593D01*
G03X1267922Y68896I-1974J813D01*
G01X1267921D01*
G03X1268058Y69648I-1997J752D01*
G01Y70632D01*
G03X1265328Y73362I-2730J0D01*
G01X1257212D01*
G02X1250400Y80174I0J6812D01*
G01Y95795D01*
X1252418Y105882D01*
X1251401Y110963D01*
Y115767D01*
X1251744Y117481D01*
X1252062Y119072D01*
X1252068Y119101D01*
X1252087Y119195D01*
X1251434Y122898D01*
X1249205Y126081D01*
X1248347Y130958D01*
X1249629Y136988D01*
X1249310Y138490D01*
X1248991Y139991D01*
X1244288Y147233D01*
X1238883Y150743D01*
X1235126Y151541D01*
X1220918Y148522D01*
X1220760D01*
X1220717Y148523D01*
X1220168Y148550D01*
X1220162D01*
X1220157Y148545D01*
X1220156D01*
X1202554Y151650D01*
X1202262D01*
X1202071Y151841D01*
X1187815Y161099D01*
X1172708Y164310D01*
X1131821Y155943D01*
X1115539Y159200D01*
X1090539Y154200D01*
X1065621Y159183D01*
X1034735Y148968D01*
X1022000D01*
G01X1274151Y69803D02*
X1274329Y69374D01*
G03X1274749Y68862I1055J437D01*
G03X1275215Y68669I466J466D01*
G01X1275653D01*
G03X1275884Y68700I1J867D01*
G03X1276266Y68923I-232J836D01*
G01X1276465Y69122D01*
G03X1276799Y69928I-806J806D01*
G03Y69957I-1216J14D01*
G03X1276800Y69959I-1087J545D01*
G01Y72675D01*
X1277409Y73546D01*
Y73547D01*
X1277410D01*
X1277907Y74257D01*
X1289022Y82407D01*
X1292091Y96851D01*
X1288497Y114134D01*
X1286845Y116672D01*
X1283367Y118933D01*
X1271479Y121459D01*
X1269386Y124681D01*
X1264578Y147298D01*
X1262091Y151028D01*
X1255565Y155265D01*
X1178867Y168790D01*
X1131475Y160433D01*
X1113139Y164100D01*
X1088068Y159086D01*
X1063149Y164070D01*
X1031044Y154351D01*
X1023700D01*
G01X1274151Y54843D02*
X1274329Y54414D01*
G03X1274749Y53902I1055J437D01*
G03X1275215Y53709I466J466D01*
G01X1275653D01*
G03X1276266Y53963I0J867D01*
G01X1276465Y54162D01*
G03X1276799Y54968I-806J806D01*
G03X1276800Y55001I-1216J53D01*
G01Y59400D01*
X1291026Y73625D01*
Y73634D01*
X1291035D01*
X1296732Y100439D01*
X1294929Y108930D01*
X1300655Y135883D01*
X1299407Y141762D01*
X1280433Y154086D01*
X1183207Y174751D01*
X1133111Y165131D01*
X1133104Y165130D01*
X1112858Y170620D01*
X1109353Y169970D01*
X1098121Y167889D01*
X1086673Y165769D01*
X1062657Y169538D01*
X1030798Y159000D01*
X1020700D01*
G01X1022340Y169960D02*
X1025153D01*
X1070718Y177994D01*
X1110001Y205500D01*
X1148460Y260248D01*
X1233532Y709272D01*
X1301567Y806434D01*
X1312877Y814353D01*
X1317290Y815131D01*
X1327267Y822116D01*
X1328878Y824415D01*
Y841436D01*
X1331053Y853777D01*
X1341476Y868683D01*
Y873200D01*
G03X1340751Y874952I-2477J1D01*
G01X1340526Y875176D01*
G01X1327928D02*
X1328153Y874952D01*
G02X1328878Y873200I-1752J-1751D01*
G01Y862602D01*
X1316769Y845310D01*
X1316300Y842645D01*
Y825817D01*
X1314241Y823758D01*
X1296862Y811590D01*
X1225742Y710048D01*
X1145626Y261700D01*
X1111003Y212255D01*
X1110928Y212180D01*
X1070271Y181814D01*
X1025154Y173860D01*
X1022728D01*
G01X1315329Y875176D02*
X1315554Y874952D01*
G02X1316279Y873200I-1752J-1751D01*
G01Y863398D01*
X1315662Y859899D01*
X1304961Y844616D01*
X1301884Y827158D01*
X1221452Y712289D01*
X1141991Y261832D01*
X1108782Y214403D01*
X1067053Y185184D01*
X1025153Y177797D01*
X1022397D01*
G01X1305931Y875176D02*
X1305706Y874952D01*
G03X1304981Y873200I1752J-1751D01*
G01Y865892D01*
X1298350Y828284D01*
X1219931Y716291D01*
X1140327Y264836D01*
X1105832Y215571D01*
X1065813Y187549D01*
X1025267Y180400D01*
X1022200D01*
G01X1293333Y875176D02*
X1293108Y874952D01*
G03X1292383Y873200I1752J-1751D01*
G01Y862017D01*
X1289500Y857900D01*
X1285634Y855193D01*
X1281378Y849115D01*
X1280000Y841300D01*
Y822070D01*
X1219415Y735546D01*
X1137343Y270091D01*
X1103086Y221164D01*
X1063168Y193213D01*
X1025153Y186510D01*
X1008518D01*
X1006948Y184940D01*
Y184390D01*
X1008267Y183071D01*
G01X1022000Y192200D02*
X1025153D01*
X1060540Y198440D01*
X1098994Y225366D01*
X1132201Y272791D01*
X1214920Y741908D01*
X1267500Y817000D01*
Y840433D01*
X1269482Y851675D01*
X1278660Y864787D01*
X1279784Y868706D01*
Y873200D01*
G02X1280509Y874952I2477J1D01*
G01X1280734Y875176D01*
G01X1022500Y196200D02*
X1025267D01*
X1058891Y202128D01*
X1096504Y228465D01*
X1128731Y274490D01*
X1213044Y752651D01*
X1252500Y809000D01*
X1254999Y823170D01*
Y823173D01*
X1255108Y823792D01*
X1254982Y824895D01*
X1254981Y824901D01*
X1254111Y832461D01*
X1254118Y832500D01*
X1257391Y851062D01*
X1267186Y865052D01*
Y873200D01*
G02X1267911Y874952I2477J1D01*
G01X1268136Y875176D01*
G01X1255537D02*
X1255312Y874952D01*
G03X1254587Y873200I1752J-1751D01*
G01Y864517D01*
X1242612Y847415D01*
X1242093Y844473D01*
Y826485D01*
X1242104Y826474D01*
Y825935D01*
X1240000Y814000D01*
X1211870Y773826D01*
X1124128Y276212D01*
X1092425Y230936D01*
X1056166Y205547D01*
X1025267Y200100D01*
X1022700D01*
G01X1022600Y208100D02*
X1041724D01*
X1052500Y210000D01*
X1088906Y235492D01*
X1117397Y276182D01*
X1214023Y824169D01*
X1213400Y827700D01*
X1216115Y843097D01*
X1221971Y851461D01*
X1237239Y862151D01*
X1241989Y868926D01*
Y873200D01*
G02X1242714Y874952I2477J1D01*
G01X1242939Y875176D01*
G01X1302731D02*
X1302956Y874952D01*
G02X1303681Y873200I-1752J-1751D01*
G01Y866009D01*
X1297119Y828794D01*
X1218700Y716801D01*
X1139096Y265346D01*
X1104898Y216505D01*
X1065303Y188780D01*
X1025153Y181700D01*
X1022494D01*
G01X1290133Y875176D02*
X1290358Y874952D01*
G02X1291083Y873200I-1752J-1751D01*
G01Y862428D01*
X1288566Y858834D01*
X1284700Y856127D01*
X1280147Y849625D01*
X1278700Y841414D01*
Y822480D01*
X1218184Y736056D01*
X1136112Y270601D01*
X1102152Y222098D01*
X1062658Y194444D01*
X1025039Y187810D01*
X1007979D01*
X1005648Y185479D01*
Y184389D01*
X1004330Y183071D01*
G01X1022000Y193500D02*
X1025039D01*
X1060030Y199671D01*
X1098060Y226300D01*
X1130970Y273301D01*
X1213689Y742418D01*
X1227300Y761857D01*
X1239945Y779915D01*
X1266200Y817410D01*
Y840547D01*
X1268251Y852185D01*
X1277470Y865354D01*
X1278484Y868889D01*
Y873200D01*
G03X1277759Y874952I-2477J1D01*
G01X1277534Y875176D01*
G01X1022494Y197500D02*
X1025153D01*
X1058381Y203359D01*
X1095570Y229399D01*
X1127500Y275000D01*
X1211813Y753161D01*
X1251269Y809510D01*
X1253794Y823831D01*
X1252797Y832500D01*
X1256160Y851572D01*
X1265886Y865462D01*
Y873200D01*
G03X1265161Y874952I-2477J1D01*
G01X1264936Y875176D01*
G01X1252337D02*
X1252562Y874952D01*
G02X1253287Y873200I-1752J-1751D01*
G01Y864927D01*
X1241381Y847925D01*
X1240793Y844587D01*
Y826485D01*
X1240783Y826475D01*
Y825935D01*
X1238769Y814510D01*
X1210639Y774336D01*
X1122897Y276722D01*
X1091491Y231870D01*
X1055656Y206778D01*
X1025153Y201400D01*
X1022494D01*
G01X1022600Y209400D02*
X1041610D01*
X1051990Y211231D01*
X1087972Y236426D01*
X1116166Y276692D01*
X1212702Y824169D01*
X1212079Y827700D01*
X1214884Y843607D01*
X1221037Y852395D01*
X1236306Y863085D01*
X1240689Y869337D01*
Y873200D01*
G03X1239964Y874952I-2477J1D01*
G01X1239739Y875176D01*
G01X1230340D02*
X1230115Y874952D01*
G03X1229390Y873200I1752J-1751D01*
G01Y870129D01*
X1212357Y845804D01*
X1112059Y276983D01*
X1085232Y238669D01*
X1050000Y214000D01*
X1038091Y211900D01*
X1022600D01*
G01X1023000Y215903D02*
X1034587D01*
X1048010Y218269D01*
X1080311Y240886D01*
X1108974Y281820D01*
X1201979Y809279D01*
X1196341Y841248D01*
X1197894Y850060D01*
Y864530D01*
G02X1199000Y867200I3776J0D01*
G01X1186246Y875176D02*
X1186021Y874952D01*
G03X1185296Y873200I1752J-1751D01*
G01Y868295D01*
X1184331Y862817D01*
X1185443Y856509D01*
X1184759Y852632D01*
X1183956Y848074D01*
X1185027Y842000D01*
Y821648D01*
X1182575Y807744D01*
X1188709Y772956D01*
X1102353Y283204D01*
X1076316Y246020D01*
X1043256Y222871D01*
X1025267Y219700D01*
X1022600D01*
G01X1023000Y223700D02*
X1025214D01*
X1041172Y226513D01*
X1069324Y246225D01*
X1095684Y283872D01*
X1175347Y735665D01*
X1163340Y803770D01*
X1169050Y836207D01*
X1163249Y869106D01*
Y873200D01*
G02X1163974Y874952I2477J1D01*
G01X1164199Y875176D01*
G01X1151600D02*
X1151375Y874952D01*
G03X1150650Y873200I1752J-1751D01*
G01Y860515D01*
X1151420Y856149D01*
X1149820Y847073D01*
X1150820Y841400D01*
Y826845D01*
X1152247Y818755D01*
X1149031Y800515D01*
X1163092Y720780D01*
X1085698Y281862D01*
X1063434Y250066D01*
X1033864Y229360D01*
X1024443Y227700D01*
X1022000D01*
G01X1139002Y875176D02*
X1138353Y874527D01*
G03X1138052Y873800I727J-727D01*
G01Y863306D01*
X1136154Y852539D01*
X1138100Y841500D01*
Y824000D01*
X1139166Y817957D01*
X1135518Y797268D01*
X1152931Y698512D01*
X1080346Y286859D01*
X1058434Y255566D01*
X1036211Y240006D01*
X1023936Y232578D01*
G01X1023592Y240478D02*
X1024007Y240841D01*
X1050832Y259625D01*
X1070000Y287000D01*
X1141455Y692249D01*
X1124521Y788281D01*
X1128364Y810098D01*
X1125400Y826911D01*
Y840400D01*
X1123568Y850788D01*
X1125453Y861477D01*
Y873200D01*
G02X1126178Y874952I2477J1D01*
G01X1126403Y875176D01*
G01X1227140D02*
X1227365Y874952D01*
G02X1228090Y873200I-1752J-1751D01*
G01Y870539D01*
X1211126Y846314D01*
X1110828Y277493D01*
X1084298Y239603D01*
X1049490Y215231D01*
X1037977Y213200D01*
X1022894D01*
G01X1195800Y867300D02*
G02X1196594Y864400I-4899J-2900D01*
G01Y850174D01*
X1195020Y841248D01*
X1200658Y809279D01*
X1107743Y282330D01*
X1079377Y241820D01*
X1047500Y219500D01*
X1034473Y217203D01*
X1022894D01*
G01X1183046Y875176D02*
X1183271Y874952D01*
G02X1183996Y873200I-1752J-1751D01*
G01Y868409D01*
X1183010Y862817D01*
X1184122Y856509D01*
X1182635Y848074D01*
X1183727Y841886D01*
Y821762D01*
X1181254Y807744D01*
X1187388Y772956D01*
X1101122Y283714D01*
X1075382Y246954D01*
X1042746Y224102D01*
X1025153Y221000D01*
X1022894D01*
G01Y225000D02*
X1025100D01*
X1040662Y227744D01*
X1068390Y247159D01*
X1094453Y284382D01*
X1174026Y735665D01*
X1162019Y803770D01*
X1167729Y836207D01*
X1161949Y868989D01*
Y873200D01*
G03X1161224Y874952I-2477J1D01*
G01X1160999Y875176D01*
G01X1022000Y229000D02*
X1024329D01*
X1033354Y230591D01*
X1062500Y251000D01*
X1084467Y282372D01*
X1161771Y720780D01*
X1147710Y800515D01*
X1150926Y818755D01*
X1149520Y826731D01*
Y841286D01*
X1148499Y847073D01*
X1150099Y856149D01*
X1149350Y860397D01*
Y873200D01*
G03X1148625Y874952I-2477J1D01*
G01X1148400Y875176D01*
G01X1023263Y233691D02*
X1035501Y241096D01*
X1057500Y256500D01*
X1079115Y287369D01*
X1151610Y698512D01*
X1134197Y797268D01*
X1137845Y817957D01*
X1136800Y823886D01*
Y841386D01*
X1134833Y852539D01*
X1136752Y863424D01*
Y873200D01*
G03X1136027Y874952I-2477J1D01*
G01X1135802Y875176D01*
G01X1022736Y241457D02*
X1023204Y241866D01*
X1049898Y260559D01*
X1068769Y287510D01*
X1140134Y692249D01*
X1123200Y788281D01*
X1127043Y810098D01*
X1124100Y826797D01*
Y840286D01*
X1122247Y850788D01*
X1124153Y861594D01*
Y873200D01*
G03X1123428Y874952I-2477J1D01*
G01X1123203Y875176D01*
G01X1072810D02*
X1073035Y874952D01*
G02X1073760Y873200I-1752J-1751D01*
G01Y865410D01*
X1074807Y859470D01*
X1072588Y846884D01*
X1073656Y840830D01*
Y823537D01*
X1074279Y820000D01*
X1069274Y791616D01*
X1100779Y612946D01*
X1056269Y360510D01*
X1004028Y285903D01*
X1001700Y272695D01*
Y264500D01*
G01X1035014Y875176D02*
X1035239Y874952D01*
G02X1035964Y873200I-1752J-1751D01*
G01Y862779D01*
X1031497Y837446D01*
X1070279Y617500D01*
X1023681Y353231D01*
X998804Y300360D01*
X998805D01*
X998789Y300326D01*
X998773Y300320D01*
X998771Y300317D01*
X993901Y272695D01*
Y264601D01*
G01X1088608Y875176D02*
X1088383Y874952D01*
G03X1087658Y873200I1752J-1751D01*
G01Y862133D01*
X1085725Y851169D01*
X1087500Y841100D01*
Y816501D01*
X1080211Y775165D01*
X1108053Y617271D01*
X1062500Y359000D01*
X1008686Y282146D01*
X1007000Y272581D01*
Y264500D01*
G01X1076010Y875176D02*
G03X1075060Y873700I672J-1476D01*
G01Y865527D01*
X1076128Y859470D01*
X1073909Y846884D01*
X1074956Y840944D01*
Y823651D01*
X1075600Y820000D01*
X1070595Y791616D01*
X1102100Y612946D01*
X1057500Y360000D01*
X1005259Y285393D01*
X1003000Y272581D01*
Y264500D01*
G01X1050813Y875176D02*
X1050588Y874952D01*
G03X1049863Y873200I1752J-1751D01*
G01Y867032D01*
X1047540Y853854D01*
X1049700Y841600D01*
Y821500D01*
X1044703Y793159D01*
X1078642Y600690D01*
X1031559Y333665D01*
X1005537Y296499D01*
X1001629Y286986D01*
X999150Y272920D01*
Y264780D01*
G01X1038214Y875176D02*
X1037989Y874952D01*
G03X1037264Y873200I1752J-1751D01*
G01Y862662D01*
X1032818Y837445D01*
X1071600Y617500D01*
X1024932Y352834D01*
X1000013Y299873D01*
X995201Y272581D01*
Y264601D01*
G01X1005700Y264500D02*
Y272695D01*
X1007455Y282656D01*
X1061269Y359510D01*
X1106732Y617271D01*
X1078890Y775165D01*
X1086200Y816615D01*
Y840986D01*
X1084404Y851169D01*
X1086358Y862251D01*
Y873200D01*
G03X1085633Y874952I-2477J1D01*
G01X1085408Y875176D01*
G01X997850Y264926D02*
Y273034D01*
X1000383Y287410D01*
X1000385Y287414D01*
X1000401Y287420D01*
X1004389Y297126D01*
X1030328Y334175D01*
X1077321Y600690D01*
X1043382Y793159D01*
X1048400Y821614D01*
Y841486D01*
X1046219Y853854D01*
X1048563Y867147D01*
Y873200D01*
G03X1047838Y874952I-2477J1D01*
G01X1047613Y875176D01*
G01X1098007D02*
X1098232Y874952D01*
G02X1098957Y873200I-1752J-1751D01*
G01Y867071D01*
X1096459Y852916D01*
X1098596Y840802D01*
Y827020D01*
X1096343Y814250D01*
X1108975Y742603D01*
X1121530Y671406D01*
X1066269Y358010D01*
X1010633Y278554D01*
X1009600Y272695D01*
Y264500D01*
G01X1014900Y264700D02*
Y272581D01*
X1015276Y274715D01*
X1073396Y357723D01*
X1130562Y681956D01*
X1109052Y803946D01*
X1112673Y824481D01*
Y840927D01*
X1110741Y851884D01*
X1112855Y863872D01*
Y873200D01*
G02X1113580Y874952I2477J1D01*
G01X1113805Y875176D01*
G01X1101207D02*
X1100982Y874952D01*
G03X1100257Y873200I1752J-1751D01*
G01Y866957D01*
X1097780Y852916D01*
X1099896Y840916D01*
Y826906D01*
X1097664Y814250D01*
X1122851Y671406D01*
X1067500Y357500D01*
X1011864Y278044D01*
X1010900Y272581D01*
Y264500D01*
G01X1110605Y875176D02*
X1110830Y874952D01*
G02X1111555Y873200I-1752J-1751D01*
G01Y863989D01*
X1109420Y851884D01*
X1111373Y840813D01*
Y824595D01*
X1107731Y803946D01*
X1129241Y681956D01*
X1072165Y358233D01*
X1014045Y275225D01*
X1013600Y272695D01*
Y264700D01*
G54D17*
X943111Y5908D03*
X935236D03*
X919486D03*
X943111Y13778D03*
X935236D03*
X919486D03*
X958856Y5908D03*
X950986D03*
X958856Y13778D03*
X950986D03*
G54D18*
G01X225000Y541300D02*
X281714D01*
X377726Y445288D01*
X562012D01*
X579900Y427400D01*
G01X649400Y234500D02*
Y230601D01*
X635863Y217064D01*
Y216308D01*
G01X642463Y241608D02*
Y226914D01*
X635190Y219641D01*
G54D19*
G01X898000Y181000D02*
X898032Y180968D01*
Y179134D01*
G01X931500Y165500D02*
Y161421D01*
X929528Y159449D01*
G01X918000Y181000D02*
X917717Y180717D01*
Y179134D01*
M02*
